G04 ================== begin FILE IDENTIFICATION RECORD ==================*
G04 Layout Name:  x887571-005_osp.brd*
G04 Film Name:    smt*
G04 File Format:  Gerber RS274X*
G04 File Origin:  Cadence Allegro 16.3-S036*
G04 Origin Date:  Thu Jul 03 00:06:57 2014*
G04 *
G04 Layer:  VIA CLASS/SOLDERMASK_TOP*
G04 Layer:  PIN/SOLDERMASK_TOP*
G04 Layer:  PACKAGE GEOMETRY/SOLDERMASK_TOP*
G04 Layer:  DRAWING FORMAT/COMMON TEXT*
G04 Layer:  BOARD GEOMETRY/SOLDERMASK_TOP*
G04 *
G04 Offset:    (0.0000 0.0000)*
G04 Mirror:    No*
G04 Mode:      Positive*
G04 Rotation:  0*
G04 FullContactRelief:  No*
G04 UndefLineWidth:     4.0000*
G04 ================== end FILE IDENTIFICATION RECORD ====================*
%FSLAX25Y25*MOIN*%
%IR0*IPPOS*OFA0.00000B0.00000*MIA0B0*SFA1.00000B1.00000*%
%ADD25R,.135X.05*%
%ADD14R,.032X.197*%
%ADD11C,.022*%
%ADD15C,.032*%
%ADD29C,.061*%
%ADD20C,.025*%
%ADD19C,.07*%
%ADD37C,.044*%
%ADD38C,.027*%
%ADD30C,.081*%
%ADD13C,.054*%
%ADD36C,.083*%
%ADD17R,.032X.032*%
%ADD32C,.058*%
%ADD40C,.079*%
%ADD26R,.054X.054*%
%ADD33R,.079X.079*%
%ADD34R,.023X.02*%
%ADD22R,.02X.023*%
%ADD31O,.014X.071*%
%ADD18R,.032X.028*%
%ADD35O,.02X.079*%
%ADD28R,.028X.032*%
%ADD12C,.12*%
%ADD24C,.22*%
%ADD39C,.15*%
%ADD27C,.106*%
%ADD16R,.372X.248*%
%ADD21C,.145*%
%ADD23C,.176*%
%ADD10C,.276*%
%ADD41C,.01*%
%ADD42C,.012*%
%ADD43C,.013*%
%ADD44C,.015*%
%ADD45C,.004*%
%ADD46C,.005*%
%ADD47C,.006*%
%ADD48C,.007*%
%ADD49C,.008*%
G75*
%LPD*%
G75*
G36*
G01X-1655236Y-63259D02*
G02X-1631850I11693J12078D01*
G01Y-74803D01*
G02X-1655236I-11693J0D01*
G01Y-63259D01*
G37*
G36*
G01X-1454252Y-10472D02*
Y24961D01*
X-1667165D01*
Y-5354D01*
X-1620709D01*
Y-10472D01*
X-1454252D01*
G37*
G36*
G01X-1434764Y-134126D02*
G02X-1411378I11693J12078D01*
G01Y-145669D01*
G02X-1434764I-11693J0D01*
G01Y-134126D01*
G37*
G36*
G01X-1190669Y-80818D02*
G02X-1167283I11693J12078D01*
G01Y-92362D01*
G02X-1190669I-11693J0D01*
G01Y-80818D01*
G37*
G36*
G01X-572559Y-104441D02*
G02X-549173I11693J12078D01*
G01Y-115984D01*
G02X-572559I-11693J0D01*
G01Y-104441D01*
G37*
G36*
G01X-316654Y-80818D02*
G02X-293268I11693J12078D01*
G01Y-92362D01*
G02X-316654I-11693J0D01*
G01Y-80818D01*
G37*
G36*
G01X-44409Y-117826D02*
G02X-21024I11693J12078D01*
G01Y-129370D01*
G02X-44409I-11693J0D01*
G01Y-117826D01*
G37*
G54D10*
X-1645906Y-167953D03*
X-1522728Y-154950D03*
X-1047676Y-78740D03*
X-652638Y-154950D03*
X-177597Y-78740D03*
X6890Y-167953D03*
G54D20*
X-1484193Y-164390D03*
Y-169390D03*
X-1489193Y-164390D03*
Y-169390D03*
X-1494193Y-164390D03*
Y-169390D03*
X-1484193Y-149390D03*
Y-154390D03*
Y-159390D03*
X-1489193Y-149390D03*
Y-154390D03*
Y-159390D03*
X-1494193Y-149390D03*
Y-154390D03*
Y-159390D03*
X-1484193Y-134390D03*
Y-139390D03*
Y-144390D03*
X-1489193Y-134390D03*
Y-139390D03*
Y-144390D03*
X-1494193Y-134390D03*
Y-139390D03*
Y-144390D03*
X-1484193Y-119390D03*
Y-124390D03*
Y-129390D03*
X-1489193Y-119390D03*
Y-124390D03*
Y-129390D03*
X-1494193Y-119390D03*
Y-124390D03*
Y-129390D03*
X-1484193Y-104390D03*
Y-109390D03*
Y-114390D03*
X-1489193Y-104390D03*
Y-109390D03*
Y-114390D03*
X-1494193Y-104390D03*
Y-109390D03*
Y-114390D03*
X-1484193Y-89390D03*
Y-94390D03*
Y-99390D03*
X-1489193Y-89390D03*
Y-94390D03*
Y-99390D03*
X-1494193Y-89390D03*
Y-94390D03*
Y-99390D03*
X-1484193Y-74390D03*
Y-79390D03*
Y-84390D03*
X-1489193Y-74390D03*
Y-79390D03*
Y-84390D03*
X-1494193Y-74390D03*
Y-79390D03*
Y-84390D03*
X-1469193Y-164390D03*
Y-169390D03*
X-1474193Y-164390D03*
Y-169390D03*
X-1479193Y-164390D03*
Y-169390D03*
X-1469193Y-149390D03*
Y-154390D03*
Y-159390D03*
X-1474193Y-149390D03*
Y-154390D03*
Y-159390D03*
X-1479193Y-149390D03*
Y-154390D03*
Y-159390D03*
X-1469193Y-134390D03*
Y-139390D03*
Y-144390D03*
X-1474193Y-134390D03*
Y-139390D03*
Y-144390D03*
X-1479193Y-134390D03*
Y-139390D03*
Y-144390D03*
X-1469193Y-119390D03*
Y-124390D03*
Y-129390D03*
X-1474193Y-119390D03*
Y-124390D03*
Y-129390D03*
X-1479193Y-119390D03*
Y-124390D03*
Y-129390D03*
X-1469193Y-104390D03*
Y-109390D03*
Y-114390D03*
X-1474193Y-104390D03*
Y-109390D03*
Y-114390D03*
X-1479193Y-104390D03*
Y-109390D03*
Y-114390D03*
X-1469193Y-89390D03*
Y-94390D03*
Y-99390D03*
X-1474193Y-89390D03*
Y-94390D03*
Y-99390D03*
X-1479193Y-89390D03*
Y-94390D03*
Y-99390D03*
X-1469193Y-74390D03*
Y-79390D03*
Y-84390D03*
X-1474193Y-74390D03*
Y-79390D03*
Y-84390D03*
X-1479193Y-74390D03*
Y-79390D03*
Y-84390D03*
X-1459193Y-164390D03*
Y-169390D03*
X-1464193Y-164390D03*
Y-169390D03*
X-1459193Y-149390D03*
Y-154390D03*
Y-159390D03*
X-1464193Y-149390D03*
Y-154390D03*
Y-159390D03*
X-1459193Y-134390D03*
Y-139390D03*
Y-144390D03*
X-1464193Y-134390D03*
Y-139390D03*
Y-144390D03*
X-1459193Y-119390D03*
Y-124390D03*
Y-129390D03*
X-1464193Y-119390D03*
Y-124390D03*
Y-129390D03*
X-1459193Y-104390D03*
Y-109390D03*
Y-114390D03*
X-1464193Y-104390D03*
Y-109390D03*
Y-114390D03*
X-1459193Y-89390D03*
Y-94390D03*
Y-99390D03*
X-1464193Y-89390D03*
Y-94390D03*
Y-99390D03*
X-1459193Y-74390D03*
Y-79390D03*
Y-84390D03*
X-1464193Y-74390D03*
Y-79390D03*
Y-84390D03*
X-619114Y-164390D03*
Y-169390D03*
X-624114Y-164390D03*
Y-169390D03*
X-619114Y-149390D03*
Y-154390D03*
Y-159390D03*
X-624114Y-149390D03*
Y-154390D03*
Y-159390D03*
X-619114Y-134390D03*
Y-139390D03*
Y-144390D03*
X-624114Y-134390D03*
Y-139390D03*
Y-144390D03*
X-619114Y-119390D03*
Y-124390D03*
Y-129390D03*
X-624114Y-119390D03*
Y-124390D03*
Y-129390D03*
X-619114Y-104390D03*
Y-109390D03*
Y-114390D03*
X-624114Y-104390D03*
Y-109390D03*
Y-114390D03*
X-619114Y-89390D03*
Y-94390D03*
Y-99390D03*
X-624114Y-89390D03*
Y-94390D03*
Y-99390D03*
X-619114Y-74390D03*
Y-79390D03*
Y-84390D03*
X-624114Y-74390D03*
Y-79390D03*
Y-84390D03*
X-604114Y-164390D03*
Y-169390D03*
X-609114Y-164390D03*
Y-169390D03*
X-614114Y-164390D03*
Y-169390D03*
X-604114Y-149390D03*
Y-154390D03*
Y-159390D03*
X-609114Y-149390D03*
Y-154390D03*
Y-159390D03*
X-614114Y-149390D03*
Y-154390D03*
Y-159390D03*
X-604114Y-134390D03*
Y-139390D03*
Y-144390D03*
X-609114Y-134390D03*
Y-139390D03*
Y-144390D03*
X-614114Y-134390D03*
Y-139390D03*
Y-144390D03*
X-604114Y-119390D03*
Y-124390D03*
Y-129390D03*
X-609114Y-119390D03*
Y-124390D03*
Y-129390D03*
X-614114Y-119390D03*
Y-124390D03*
Y-129390D03*
X-604114Y-104390D03*
Y-109390D03*
Y-114390D03*
X-609114Y-104390D03*
Y-109390D03*
Y-114390D03*
X-614114Y-104390D03*
Y-109390D03*
Y-114390D03*
X-604114Y-89390D03*
Y-94390D03*
Y-99390D03*
X-609114Y-89390D03*
Y-94390D03*
Y-99390D03*
X-614114Y-89390D03*
Y-94390D03*
Y-99390D03*
X-604114Y-74390D03*
Y-79390D03*
Y-84390D03*
X-609114Y-74390D03*
Y-79390D03*
Y-84390D03*
X-614114Y-74390D03*
Y-79390D03*
Y-84390D03*
X-589114Y-164390D03*
Y-169390D03*
X-594114Y-164390D03*
Y-169390D03*
X-599114Y-164390D03*
Y-169390D03*
X-589114Y-149390D03*
Y-154390D03*
Y-159390D03*
X-594114Y-149390D03*
Y-154390D03*
Y-159390D03*
X-599114Y-149390D03*
Y-154390D03*
Y-159390D03*
X-589114Y-134390D03*
Y-139390D03*
Y-144390D03*
X-594114Y-134390D03*
Y-139390D03*
Y-144390D03*
X-599114Y-134390D03*
Y-139390D03*
Y-144390D03*
X-589114Y-119390D03*
Y-124390D03*
Y-129390D03*
X-594114Y-119390D03*
Y-124390D03*
Y-129390D03*
X-599114Y-119390D03*
Y-124390D03*
Y-129390D03*
X-589114Y-104390D03*
Y-109390D03*
Y-114390D03*
X-594114Y-104390D03*
Y-109390D03*
Y-114390D03*
X-599114Y-104390D03*
Y-109390D03*
Y-114390D03*
X-589114Y-89390D03*
Y-94390D03*
Y-99390D03*
X-594114Y-89390D03*
Y-94390D03*
Y-99390D03*
X-599114Y-89390D03*
Y-94390D03*
Y-99390D03*
X-589114Y-74390D03*
Y-79390D03*
Y-84390D03*
X-594114Y-74390D03*
Y-79390D03*
Y-84390D03*
X-599114Y-74390D03*
Y-79390D03*
Y-84390D03*
G54D11*
X-1656906Y-167953D03*
X-1645906Y-178953D03*
X-1653906Y-175453D03*
X-1653406Y-159953D03*
X-1645906Y-156953D03*
X-1634906Y-167953D03*
X-1637906Y-175453D03*
X-1638406Y-159953D03*
X-1530728Y-162450D03*
X-1533728Y-154950D03*
X-1530228Y-146950D03*
X-1522728Y-165950D03*
X-1514728Y-162450D03*
X-1515228Y-146950D03*
X-1522728Y-143950D03*
X-1511728Y-154950D03*
X-1058676Y-78740D03*
X-1047676Y-89740D03*
X-1055676Y-86240D03*
X-1055176Y-70740D03*
X-1047676Y-67740D03*
X-1039676Y-86240D03*
X-1040176Y-70740D03*
X-1036676Y-78740D03*
X-663638Y-154950D03*
X-652638Y-165950D03*
X-660638Y-162450D03*
X-660138Y-146950D03*
X-652638Y-143950D03*
X-641638Y-154950D03*
X-644638Y-162450D03*
X-645138Y-146950D03*
X-177597Y-89740D03*
X-185597Y-86240D03*
X-188597Y-78740D03*
X-185097Y-70740D03*
X-177597Y-67740D03*
X-169597Y-86240D03*
X-170097Y-70740D03*
X-166597Y-78740D03*
X-4110Y-167953D03*
X6890Y-178953D03*
X-1110Y-175453D03*
X14390Y-159953D03*
X-610D03*
X6890Y-156953D03*
X17890Y-167953D03*
X14890Y-175453D03*
G54D21*
X-1410000Y0D03*
X0Y-136453D03*
X0Y0D03*
G54D12*
X-1646000Y-140700D03*
X-836000Y-172000D03*
Y500D03*
X-28500Y-169500D03*
Y500D03*
G54D30*
X-1278150Y-142362D03*
X-1212008D03*
X-408071D03*
X-341929D03*
G54D31*
X-1263189Y-172598D03*
X-1266339D03*
X-1269488D03*
X-1272638D03*
X-1274213Y-162756D03*
X-1271063D03*
X-1267913D03*
X-1264764D03*
X-1247441Y-172598D03*
X-1250591D03*
X-1253740D03*
X-1256890D03*
X-1260039D03*
X-1261614Y-162756D03*
X-1258465D03*
X-1255315D03*
X-1252165D03*
X-1249016D03*
X-1231693Y-172598D03*
X-1234843D03*
X-1237992D03*
X-1241142D03*
X-1244291D03*
X-1245866Y-162756D03*
X-1242717D03*
X-1239567D03*
X-1236417D03*
X-1233268D03*
X-1215945Y-172598D03*
X-1219094D03*
X-1222244D03*
X-1225394D03*
X-1228543D03*
X-1230118Y-162756D03*
X-1226968D03*
X-1223819D03*
X-1220669D03*
X-1217520D03*
X-396260Y-172598D03*
X-399409D03*
X-402559D03*
X-404134Y-162756D03*
X-400984D03*
X-397835D03*
X-380512Y-172598D03*
X-383661D03*
X-386811D03*
X-389961D03*
X-393110D03*
X-394685Y-162756D03*
X-391535D03*
X-388386D03*
X-385236D03*
X-382087D03*
X-364764Y-172598D03*
X-367913D03*
X-371063D03*
X-374213D03*
X-377362D03*
X-378937Y-162756D03*
X-375787D03*
X-372638D03*
X-369488D03*
X-366339D03*
X-349016Y-172598D03*
X-352165D03*
X-355315D03*
X-358465D03*
X-361614D03*
X-363189Y-162756D03*
X-360039D03*
X-356890D03*
X-353740D03*
X-350591D03*
X-345866Y-172598D03*
X-347441Y-162756D03*
G54D22*
X-1391300Y-133200D03*
Y-136800D03*
X-1322228Y-85650D03*
Y-82050D03*
X-1059228Y-49050D03*
Y-52650D03*
X-1054228Y-44050D03*
Y-47650D03*
X-1048000Y-47611D03*
Y-43989D03*
X-1056000Y-37300D03*
Y-33700D03*
Y-13300D03*
Y-9700D03*
X-519200Y-123700D03*
Y-127300D03*
X-453628Y-85550D03*
Y-81950D03*
X-187650Y-48550D03*
Y-52150D03*
X-182650Y-43550D03*
Y-47150D03*
X-177150Y-47161D03*
Y-43539D03*
X-184150Y-38150D03*
Y-34550D03*
Y-12650D03*
Y-9050D03*
G54D40*
X-806854Y-99635D03*
Y-83100D03*
X-785200Y-99635D03*
G54D13*
X-1649000Y-121500D03*
Y-105752D03*
Y-113626D03*
Y-97878D03*
X-1327756Y-175039D03*
Y-167165D03*
Y-159291D03*
Y-143543D03*
Y-135669D03*
X-1319882Y-175039D03*
Y-167165D03*
Y-159291D03*
Y-143543D03*
Y-135669D03*
Y-127795D03*
X-1296260Y-175039D03*
X-1304134D03*
X-1296260Y-167165D03*
X-1304134D03*
X-1296260Y-159291D03*
X-1304134D03*
X-1296260Y-143543D03*
X-1304134D03*
X-1296260Y-135669D03*
X-1304134D03*
X-1296260Y-127795D03*
X-1304134D03*
X-793728Y-161850D03*
Y-153976D03*
Y-138228D03*
Y-146102D03*
X-457677Y-175039D03*
Y-167165D03*
Y-159291D03*
Y-143543D03*
Y-135669D03*
X-449803Y-175039D03*
Y-167165D03*
Y-159291D03*
Y-143543D03*
Y-135669D03*
Y-127795D03*
X-426181Y-175039D03*
X-434055D03*
X-426181Y-167165D03*
X-434055D03*
X-426181Y-159291D03*
X-434055D03*
X-426181Y-143543D03*
X-434055D03*
X-426181Y-135669D03*
X-434055D03*
X-426181Y-127795D03*
X-434055D03*
G54D41*
G01X-1184000Y-502500D02*
Y-512500D01*
G01X-1186683Y-502500D02*
X-1181317D01*
G01X-1176833Y-512500D02*
Y-502500D01*
X-1173917D01*
X-1172983Y-503000D01*
X-1172400Y-503667D01*
X-1172167Y-505000D01*
X-1172400Y-506333D01*
X-1173100Y-507167D01*
X-1173917Y-507667D01*
X-1176833D01*
G01X-1173917D02*
X-1172167Y-512500D01*
G01X-1167917D02*
X-1165000Y-502500D01*
X-1162083Y-512500D01*
G01X-1163133Y-509000D02*
X-1166867D01*
G01X-1155500Y-512500D02*
Y-508000D01*
X-1157833Y-502500D01*
G01X-1153167D02*
X-1155500Y-508000D01*
G01X-1135567Y-507167D02*
X-1135100Y-506667D01*
X-1134750Y-505834D01*
X-1134517Y-504667D01*
X-1134750Y-503667D01*
X-1135217Y-503000D01*
X-1136033Y-502500D01*
X-1139183D01*
Y-512500D01*
X-1135333D01*
X-1134517Y-511833D01*
X-1134050Y-510833D01*
X-1133817Y-509667D01*
X-1134050Y-508500D01*
X-1134750Y-507500D01*
X-1135567Y-507167D01*
X-1139183D01*
G01X-1129917Y-512500D02*
X-1127000Y-502500D01*
X-1124083Y-512500D01*
G01X-1125133Y-509000D02*
X-1128867D01*
G01X-1114933Y-503333D02*
X-1115633Y-502833D01*
X-1116450Y-502500D01*
X-1117383D01*
X-1118433Y-503000D01*
X-1119250Y-503833D01*
X-1119833Y-504833D01*
X-1120300Y-506500D01*
X-1120417Y-508000D01*
X-1120183Y-509500D01*
X-1119833Y-510500D01*
X-1119133Y-511500D01*
X-1118317Y-512167D01*
X-1117500Y-512500D01*
X-1116683D01*
X-1115867Y-512167D01*
X-1115167Y-511667D01*
X-1114583Y-511000D01*
G01X-1110567Y-512500D02*
Y-502500D01*
G01X-1106133D02*
X-1110567Y-508667D01*
G01X-1105433Y-512500D02*
X-1108583Y-505834D01*
G01X-1100833Y-512500D02*
Y-502500D01*
X-1098033D01*
X-1097100Y-503000D01*
X-1096400Y-504167D01*
X-1096167Y-505500D01*
X-1096400Y-506833D01*
X-1096983Y-507833D01*
X-1098033Y-508334D01*
X-1100833D01*
G01X-1091333Y-502500D02*
Y-512500D01*
X-1086667D01*
G01X-1082417D02*
X-1079500Y-502500D01*
X-1076583Y-512500D01*
G01X-1077633Y-509000D02*
X-1081367D01*
G01X-1072683Y-512500D02*
Y-502500D01*
X-1067317Y-512500D01*
Y-502500D01*
G01X-1058167Y-512500D02*
X-1062833D01*
Y-502500D01*
X-1058167D01*
G01X-1060033Y-507333D02*
X-1062833D01*
G01X-1043717Y-512500D02*
Y-502500D01*
X-1039283D01*
G01X-1040917Y-507333D02*
X-1043717D01*
G01X-1034917Y-512500D02*
X-1032000Y-502500D01*
X-1029083Y-512500D01*
G01X-1030133Y-509000D02*
X-1033867D01*
G01X-1021567Y-507167D02*
X-1021100Y-506667D01*
X-1020750Y-505834D01*
X-1020517Y-504667D01*
X-1020750Y-503667D01*
X-1021217Y-503000D01*
X-1022033Y-502500D01*
X-1025183D01*
Y-512500D01*
X-1021333D01*
X-1020517Y-511833D01*
X-1020050Y-510833D01*
X-1019817Y-509667D01*
X-1020050Y-508500D01*
X-1020750Y-507500D01*
X-1021567Y-507167D01*
X-1025183D01*
G01X-1002567D02*
X-1002100Y-506667D01*
X-1001750Y-505834D01*
X-1001517Y-504667D01*
X-1001750Y-503667D01*
X-1002217Y-503000D01*
X-1003033Y-502500D01*
X-1006183D01*
Y-512500D01*
X-1002333D01*
X-1001517Y-511833D01*
X-1001050Y-510833D01*
X-1000817Y-509667D01*
X-1001050Y-508500D01*
X-1001750Y-507500D01*
X-1002567Y-507167D01*
X-1006183D01*
G01X-985083Y-515833D02*
X-986250Y-514167D01*
X-986833Y-512500D01*
Y-505834D01*
X-986250Y-504167D01*
X-985083Y-502500D01*
G01X-975000Y-512500D02*
X-975933Y-512333D01*
X-976750Y-511667D01*
X-977450Y-510667D01*
X-977917Y-509500D01*
X-978150Y-508167D01*
Y-506833D01*
X-977917Y-505500D01*
X-977450Y-504333D01*
X-976750Y-503333D01*
X-975933Y-502667D01*
X-975000Y-502500D01*
X-974067Y-502667D01*
X-973250Y-503333D01*
X-972550Y-504333D01*
X-972083Y-505500D01*
X-971850Y-506833D01*
Y-508167D01*
X-972083Y-509500D01*
X-972550Y-510667D01*
X-973250Y-511667D01*
X-974067Y-512333D01*
X-975000Y-512500D01*
G01X-967950Y-511167D02*
X-967017Y-512000D01*
X-965967Y-512500D01*
X-965033D01*
X-964100Y-512000D01*
X-963400Y-511167D01*
X-963050Y-510000D01*
X-963283Y-508834D01*
X-963867Y-507833D01*
X-964917Y-507167D01*
X-966317Y-506833D01*
X-967133Y-506167D01*
X-967483Y-505000D01*
X-967250Y-503833D01*
X-966667Y-503000D01*
X-965850Y-502500D01*
X-965033D01*
X-964217Y-502833D01*
X-963517Y-503667D01*
G01X-958333Y-512500D02*
Y-502500D01*
X-955533D01*
X-954600Y-503000D01*
X-953900Y-504167D01*
X-953667Y-505500D01*
X-953900Y-506833D01*
X-954483Y-507833D01*
X-955533Y-508334D01*
X-958333D01*
G01X-945917Y-515833D02*
X-944750Y-514167D01*
X-944167Y-512500D01*
Y-505834D01*
X-944750Y-504167D01*
X-945917Y-502500D01*
G01X-902000Y-470000D02*
Y-460000D01*
X-903400Y-462000D01*
G01Y-470000D02*
X-900600D01*
G01X-892500Y-470333D02*
X-892733Y-470167D01*
Y-469833D01*
X-892500Y-469667D01*
X-892267Y-469833D01*
Y-470167D01*
X-892500Y-470333D01*
G01Y-465834D02*
X-892733Y-465667D01*
Y-465333D01*
X-892500Y-465167D01*
X-892267Y-465333D01*
Y-465667D01*
X-892500Y-465834D01*
G01X-883000Y-470000D02*
Y-460000D01*
X-884400Y-462000D01*
G01Y-470000D02*
X-881600D01*
G01X-785060Y-472187D02*
X-784127Y-473020D01*
X-783077Y-473520D01*
X-782143D01*
X-781210Y-473020D01*
X-780510Y-472187D01*
X-780160Y-471020D01*
X-780393Y-469854D01*
X-780977Y-468853D01*
X-782027Y-468187D01*
X-783427Y-467853D01*
X-784243Y-467187D01*
X-784593Y-466020D01*
X-784360Y-464853D01*
X-783777Y-464020D01*
X-782960Y-463520D01*
X-782143D01*
X-781327Y-463853D01*
X-780627Y-464687D01*
G01X-775560Y-473520D02*
Y-463520D01*
G01X-770660D02*
Y-473520D01*
G01Y-468520D02*
X-775560D01*
G01X-766527Y-473520D02*
X-763610Y-463520D01*
X-760693Y-473520D01*
G01X-761743Y-470020D02*
X-765477D01*
G01X-757610Y-463520D02*
X-755977Y-473520D01*
X-754110Y-463520D01*
X-752243Y-473520D01*
X-750610Y-463520D01*
G01X-668067Y-470500D02*
X-667367Y-471667D01*
X-666433Y-472333D01*
X-665383Y-472500D01*
X-664450Y-472333D01*
X-663517Y-471500D01*
X-662933Y-470500D01*
X-662817Y-469500D01*
X-663050Y-468334D01*
X-663867Y-467500D01*
X-664683Y-467167D01*
X-665733D01*
G01X-664683D02*
X-663983Y-466667D01*
X-663400Y-465834D01*
X-663167Y-464833D01*
X-663400Y-463833D01*
X-663983Y-463000D01*
X-665033Y-462500D01*
X-666083Y-462667D01*
X-667133Y-463333D01*
G01X-656000Y-462500D02*
X-656933Y-462833D01*
X-657633Y-463667D01*
X-658100Y-464667D01*
X-658450Y-466000D01*
X-658567Y-467500D01*
X-658450Y-469000D01*
X-658100Y-470333D01*
X-657633Y-471334D01*
X-656933Y-472167D01*
X-656000Y-472500D01*
X-655067Y-472167D01*
X-654367Y-471334D01*
X-653900Y-470333D01*
X-653550Y-469000D01*
X-653433Y-467500D01*
X-653550Y-466000D01*
X-653900Y-464667D01*
X-654367Y-463667D01*
X-655067Y-462833D01*
X-656000Y-462500D01*
G01X-648017Y-469167D02*
X-644983D01*
G01X-639917Y-472500D02*
X-637000Y-462500D01*
X-634083Y-472500D01*
G01X-635133Y-469000D02*
X-638867D01*
G01X-629833Y-472500D02*
Y-462500D01*
X-627033D01*
X-626100Y-463000D01*
X-625400Y-464167D01*
X-625167Y-465500D01*
X-625400Y-466833D01*
X-625983Y-467833D01*
X-627033Y-468334D01*
X-629833D01*
G01X-620333Y-472500D02*
Y-462500D01*
X-617417D01*
X-616483Y-463000D01*
X-615900Y-463667D01*
X-615667Y-465000D01*
X-615900Y-466333D01*
X-616600Y-467167D01*
X-617417Y-467667D01*
X-620333D01*
G01X-617417D02*
X-615667Y-472500D01*
G01X-610017Y-469167D02*
X-606983D01*
G01X-599000Y-472500D02*
Y-462500D01*
X-600400Y-464500D01*
G01Y-472500D02*
X-597600D01*
G01X-588100D02*
Y-462500D01*
X-592417Y-469667D01*
X-586583D01*
G54D23*
X-1356889Y-167165D03*
Y-118937D03*
X-1051613Y-167165D03*
Y-118937D03*
X-486810Y-167165D03*
Y-118937D03*
X-181534Y-167165D03*
Y-118937D03*
G54D32*
X-1141240Y-132520D03*
Y-112835D03*
Y-94331D03*
X-1132087Y-150630D03*
X-1113189D03*
X-1094291D03*
X-1085138Y-132520D03*
Y-112835D03*
Y-94331D03*
X-271161Y-132520D03*
Y-112835D03*
Y-94331D03*
X-262008Y-150630D03*
X-243110D03*
X-224213D03*
X-215059Y-132520D03*
Y-112835D03*
Y-94331D03*
G54D14*
X-1654488Y7244D03*
X-1649488D03*
X-1644488D03*
X-1639488D03*
X-1634488D03*
X-1629488D03*
G54D42*
G01X-1174900Y-473500D02*
X-1171300Y-466100D01*
X-1171800Y-465700D01*
X-1175900Y-473200D01*
X-1176200Y-471200D01*
X-1172500Y-465400D01*
X-1175700Y-471300D01*
X-1176500Y-469800D01*
X-1172900Y-464900D01*
X-1173600Y-451800D01*
X-1173700Y-449900D01*
X-1182100D01*
X-1187400Y-473000D01*
X-1182400D01*
X-1177800Y-456000D01*
X-1177000Y-455900D01*
X-1176100Y-468500D01*
X-1173700Y-464500D01*
X-1174600Y-450800D01*
X-1181500Y-450900D01*
X-1186400Y-472100D01*
X-1183100D01*
X-1178300Y-454800D01*
X-1176600Y-455000D01*
X-1175500Y-466300D01*
X-1174600Y-464300D01*
X-1175400Y-451700D01*
X-1181000Y-451800D01*
X-1185300Y-471300D01*
X-1183800Y-471400D01*
X-1179000Y-454300D01*
X-1176200D01*
X-1175200Y-462200D01*
X-1176200Y-452500D01*
X-1180500Y-452800D01*
X-1184300Y-470600D01*
X-1179700Y-453400D01*
X-1176800D01*
G01X-1182820Y-448900D02*
X-1188360Y-473900D01*
X-1181580D01*
X-1177300Y-456700D01*
X-1176920Y-473900D01*
X-1172260D01*
X-1163400Y-456920D01*
X-1167240Y-473900D01*
X-1160380D01*
X-1154840Y-448900D01*
X-1164540D01*
X-1172540Y-464820D01*
X-1172880Y-448900D01*
X-1182820D01*
G01X-1155800Y-449500D02*
X-1161100Y-472900D01*
X-1166100Y-473000D01*
X-1166000Y-471900D01*
X-1161800Y-472100D01*
X-1161300Y-471000D01*
X-1165900Y-471100D01*
X-1165700Y-470000D01*
X-1161300D01*
X-1160800Y-469200D01*
X-1165300Y-469100D01*
X-1165200Y-468100D01*
X-1160700D01*
X-1160400Y-467100D01*
X-1165100Y-467200D01*
X-1164900Y-466300D01*
X-1160300Y-466200D01*
X-1160000Y-465200D01*
X-1164700Y-465300D01*
X-1164400Y-464200D01*
X-1159700Y-464300D01*
X-1159300Y-463100D01*
X-1164700Y-463500D01*
X-1164000Y-462500D01*
X-1159500Y-462600D01*
X-1159000Y-461700D01*
X-1163900D01*
X-1163600Y-460600D01*
X-1159100Y-460800D01*
X-1158800Y-459900D01*
X-1163200D01*
X-1163100Y-459200D01*
X-1158800D01*
X-1158300Y-458500D01*
X-1163000Y-458400D01*
X-1162900Y-457800D01*
X-1158400Y-457900D01*
X-1158200Y-457200D01*
X-1162500Y-457000D01*
X-1163100Y-456500D01*
X-1157800D01*
X-1157500Y-455500D01*
X-1156600Y-449800D01*
X-1164000D01*
X-1164500Y-450700D01*
X-1157600D01*
X-1157800Y-451700D01*
X-1165000Y-451600D01*
X-1165400Y-452400D01*
X-1157900Y-452500D01*
X-1157800Y-453500D01*
X-1165900Y-453200D01*
X-1166200Y-453900D01*
X-1158000Y-454300D01*
X-1158300Y-455300D01*
X-1166600Y-454800D01*
X-1158900Y-455900D01*
X-1167000Y-455600D01*
X-1163500Y-456400D01*
X-1167300Y-456300D01*
X-1171700Y-465200D01*
X-1169200Y-466400D01*
X-1164500Y-457200D01*
X-1166900Y-457100D01*
X-1170600Y-465200D01*
X-1169500Y-465500D01*
X-1166000Y-457800D01*
G01X-1170300Y-466300D02*
X-1174000Y-473600D01*
G01X-1169500Y-466900D02*
X-1172800Y-473000D01*
G01X-1152800Y-456400D02*
X-1156600Y-473100D01*
X-1152200Y-473000D01*
X-1148300Y-456600D01*
X-1149500D01*
X-1152900Y-472000D01*
X-1155600Y-472300D01*
X-1152100Y-456500D01*
X-1150400Y-456400D01*
X-1153600Y-471200D01*
X-1154500Y-471400D01*
X-1151400Y-457200D01*
G01X-1153420Y-455700D02*
X-1157540Y-473900D01*
X-1151380D01*
X-1147440Y-455700D01*
X-1153420D01*
G01X-1151600Y-450100D02*
X-1146700Y-450000D01*
X-1147000Y-451000D01*
X-1151700D01*
G01X-1152020Y-448900D02*
X-1152660Y-451900D01*
X-1146380D01*
X-1145740Y-448900D01*
X-1152020D01*
G01X-1129400Y-468900D02*
X-1131800Y-471900D01*
X-1136500Y-473700D01*
X-1142100Y-473600D01*
X-1144600Y-472300D01*
X-1145800Y-471000D01*
X-1146400Y-469500D01*
X-1146700Y-467600D01*
X-1146500Y-464600D01*
X-1145400Y-461200D01*
X-1143500Y-459100D01*
X-1140200Y-456900D01*
X-1136100Y-456200D01*
X-1132300Y-456400D01*
X-1129400Y-457900D01*
X-1127500Y-460900D01*
X-1132500Y-461000D01*
X-1133400Y-459200D01*
X-1135100Y-458100D01*
X-1136800Y-458000D01*
X-1138600Y-458900D01*
X-1140300Y-460700D01*
X-1141800Y-463600D01*
X-1142400Y-466600D01*
X-1141500Y-470400D01*
X-1140200Y-471500D01*
X-1138300Y-471600D01*
X-1136300Y-471400D01*
X-1134500Y-469100D01*
X-1130300Y-469000D01*
X-1132500Y-471200D01*
X-1134900Y-472000D01*
X-1137200Y-472800D01*
X-1142300Y-472700D01*
X-1144900Y-470600D01*
X-1145800Y-467400D01*
X-1145500Y-465100D01*
X-1144700Y-462000D01*
X-1143300Y-460200D01*
X-1139800Y-457700D01*
X-1135400Y-457000D01*
X-1131300Y-457600D01*
X-1128800Y-460100D01*
X-1132100D01*
X-1134300Y-457900D01*
X-1130100Y-458800D01*
X-1129500Y-459400D01*
X-1132600Y-459000D01*
G01X-1133300Y-461900D02*
Y-461420D01*
X-1133640Y-460240D01*
X-1134300Y-459200D01*
X-1135200Y-458900D01*
X-1136580D01*
X-1138060Y-459820D01*
X-1139360Y-461000D01*
X-1140240Y-462220D01*
X-1140880Y-463920D01*
X-1141300Y-465380D01*
X-1141500Y-467060D01*
Y-468020D01*
X-1141020Y-469220D01*
X-1139780Y-470700D01*
X-1137160D01*
X-1135840Y-469500D01*
X-1134980Y-468200D01*
X-1134940Y-468100D01*
X-1128180D01*
X-1128240Y-468240D01*
X-1128840Y-469340D01*
X-1129020Y-469800D01*
X-1129740Y-470700D01*
X-1130500Y-471460D01*
X-1131660Y-472420D01*
X-1132820Y-473200D01*
X-1133740Y-473740D01*
X-1136380Y-474500D01*
X-1141640D01*
X-1142540Y-474320D01*
X-1144220Y-473760D01*
X-1144900Y-473240D01*
X-1146240Y-471900D01*
X-1146780Y-471180D01*
X-1146940Y-470880D01*
X-1147320Y-469660D01*
X-1147500Y-468640D01*
Y-464780D01*
X-1146940Y-462540D01*
X-1146380Y-461580D01*
X-1145980Y-460780D01*
X-1145420Y-459880D01*
X-1143700Y-458140D01*
X-1142740Y-457380D01*
X-1142000Y-456820D01*
X-1140240Y-456040D01*
X-1139500Y-455660D01*
X-1138800Y-455480D01*
X-1137260Y-455300D01*
X-1134320D01*
X-1132020Y-455500D01*
X-1130940Y-455860D01*
X-1130580Y-456020D01*
X-1129260Y-456780D01*
X-1128940Y-457100D01*
X-1127820Y-458420D01*
X-1127060Y-460300D01*
X-1126900Y-460800D01*
Y-461900D01*
X-1133300D01*
G01X-1137900Y-458000D02*
X-1140300Y-459100D01*
X-1142500Y-460900D01*
X-1143900Y-462600D01*
X-1144800Y-467600D01*
X-1144200Y-470000D01*
X-1141000Y-472300D01*
X-1136400Y-472200D01*
X-1131600Y-469600D01*
X-1135400Y-470400D01*
X-1141100Y-471400D01*
X-1142100Y-470700D01*
X-1142700Y-469000D01*
X-1143100Y-467100D01*
X-1142700Y-464100D01*
X-1140500Y-459900D01*
X-1143400Y-463700D01*
X-1143600Y-465700D01*
X-1143900Y-467700D01*
X-1143000Y-469900D01*
G01X-1113500Y-459200D02*
X-1123500Y-459300D01*
X-1123700Y-460100D01*
X-1114300Y-460000D01*
X-1116500Y-460800D01*
X-1124200Y-461000D01*
X-1124400Y-461900D01*
X-1117600Y-461800D01*
X-1118800Y-462800D01*
X-1124500Y-462700D01*
X-1124600Y-463600D01*
X-1119300Y-463700D01*
X-1120100Y-464800D01*
X-1125000Y-464600D01*
Y-465500D01*
X-1120600Y-465700D01*
X-1120800Y-466700D01*
X-1125300Y-466500D01*
X-1125500Y-467400D01*
X-1121000Y-467600D01*
X-1121200Y-468700D01*
X-1125600Y-468400D01*
X-1125900Y-469100D01*
X-1121500Y-469500D01*
X-1121700Y-470700D01*
X-1126100Y-470000D01*
X-1126200Y-470700D01*
X-1121900Y-471200D01*
X-1122100Y-472000D01*
X-1126300Y-471700D01*
X-1126700Y-472300D01*
X-1122100Y-472700D01*
X-1122200Y-473100D01*
X-1126800Y-473200D01*
G01X-1114060Y-460760D02*
X-1114840Y-460920D01*
X-1115740Y-461140D01*
X-1116880Y-461820D01*
X-1117700Y-462640D01*
X-1118620Y-463340D01*
X-1118840Y-464020D01*
X-1119440Y-464820D01*
X-1119660Y-465480D01*
X-1120060Y-466280D01*
X-1120280Y-466960D01*
X-1120480Y-468360D01*
X-1120680Y-468940D01*
X-1120880Y-469940D01*
X-1121080Y-470540D01*
X-1121700Y-472980D01*
X-1121820Y-473900D01*
X-1127640D01*
X-1126920Y-471060D01*
X-1126720Y-470440D01*
X-1126500Y-468800D01*
X-1126320Y-467860D01*
X-1126120Y-467260D01*
X-1125920Y-466260D01*
X-1125720Y-465660D01*
X-1125300Y-464000D01*
X-1125120Y-462220D01*
X-1124920Y-461660D01*
X-1124720Y-460660D01*
X-1124520Y-460060D01*
X-1123720Y-456800D01*
X-1123580Y-455700D01*
X-1117880D01*
X-1118100Y-456160D01*
Y-458740D01*
X-1116500Y-457160D01*
X-1115780Y-456620D01*
X-1114680Y-456060D01*
X-1113560Y-455680D01*
X-1112460Y-455500D01*
X-1111720D01*
X-1112460Y-458440D01*
X-1114060Y-460760D01*
G01X-1123100Y-456500D02*
X-1118900Y-456600D01*
X-1118800Y-457600D01*
X-1123100Y-457500D01*
X-1123300Y-458500D01*
X-1113100Y-458400D01*
X-1112600Y-456400D01*
X-1116100Y-457600D01*
X-1113500D01*
G01X-1105100Y-471100D02*
X-1104060D01*
X-1103780Y-470820D01*
X-1103200Y-470640D01*
X-1102080Y-469740D01*
X-1100800Y-468240D01*
X-1100380Y-467400D01*
X-1100180Y-467100D01*
X-1099960Y-466660D01*
X-1099540Y-465720D01*
X-1099320Y-465060D01*
X-1099100Y-464180D01*
Y-461220D01*
X-1099360Y-460200D01*
X-1099660Y-459900D01*
X-1100700Y-458640D01*
X-1101220Y-458300D01*
X-1103340D01*
X-1103700Y-458640D01*
X-1105300Y-459840D01*
X-1105760Y-460320D01*
X-1106180Y-460940D01*
X-1107060Y-462020D01*
X-1107260Y-462880D01*
X-1107660Y-463660D01*
X-1108100Y-465000D01*
Y-468640D01*
X-1107620Y-469600D01*
X-1107140Y-470340D01*
X-1105980Y-471100D01*
X-1105100D01*
G01X-1112540Y-460460D02*
X-1110680Y-458140D01*
X-1109940Y-457580D01*
X-1109000Y-456840D01*
X-1108480Y-456660D01*
X-1107940Y-456400D01*
X-1107740Y-456200D01*
X-1107480Y-456060D01*
X-1106880Y-455860D01*
X-1106480Y-455660D01*
X-1105960Y-455480D01*
X-1104600Y-455300D01*
X-1103440Y-455100D01*
X-1100940D01*
X-1098240Y-455480D01*
X-1097720Y-455660D01*
X-1097020Y-456020D01*
X-1096180Y-456640D01*
X-1095620Y-456820D01*
X-1095540Y-456900D01*
X-1094200Y-458440D01*
X-1093660Y-459520D01*
X-1093460Y-460100D01*
X-1093100Y-461020D01*
Y-464400D01*
X-1093420Y-465360D01*
X-1094300Y-465520D01*
X-1094720Y-465740D01*
X-1095320Y-465940D01*
X-1096120Y-466340D01*
X-1096720Y-466540D01*
X-1097100Y-466720D01*
X-1098100Y-466920D01*
X-1098520Y-467140D01*
X-1099160Y-467360D01*
X-1101180Y-468700D01*
X-1094660D01*
X-1095220Y-469800D01*
X-1095560Y-470320D01*
X-1097480Y-472220D01*
X-1099940Y-473740D01*
X-1102580Y-474500D01*
X-1108800D01*
X-1109300Y-474340D01*
X-1111220Y-473560D01*
X-1111720Y-473240D01*
X-1113240Y-471720D01*
X-1113560Y-471240D01*
X-1113760Y-470660D01*
X-1114140Y-469980D01*
X-1114320Y-469120D01*
X-1114500Y-468680D01*
Y-464980D01*
X-1114320Y-464260D01*
X-1114140Y-463720D01*
X-1113940Y-463320D01*
X-1113720Y-462660D01*
X-1113560Y-462000D01*
X-1111880Y-460320D01*
X-1112540Y-460460D01*
G01X-1099300Y-466400D02*
X-1093800Y-464400D01*
X-1093900Y-461100D01*
X-1094800Y-459000D01*
X-1096800Y-457300D01*
X-1100000Y-456100D01*
X-1102800Y-455900D01*
X-1106300Y-456300D01*
X-1109600Y-458100D01*
X-1111400Y-460500D01*
X-1112900Y-462600D01*
X-1113600Y-465600D01*
X-1113500Y-469100D01*
X-1112100Y-471900D01*
X-1109600Y-473300D01*
X-1105700Y-473800D01*
X-1101000Y-473400D01*
X-1098200Y-471800D01*
X-1096600Y-470100D01*
X-1096000Y-469500D01*
X-1100800Y-469700D01*
X-1102300Y-471100D01*
X-1097900Y-470400D01*
X-1100300Y-471800D01*
X-1103200Y-471400D01*
X-1100600Y-472600D01*
X-1103000D01*
X-1103700Y-471900D01*
X-1103400Y-473000D01*
X-1104600Y-471900D01*
X-1106200D01*
X-1104100Y-473100D01*
X-1107200Y-472700D01*
X-1110100Y-472100D01*
X-1111500Y-470900D01*
X-1112600Y-468600D01*
X-1112700Y-466000D01*
X-1112400Y-463700D01*
X-1111400Y-461600D01*
X-1109600Y-459500D01*
X-1108100Y-458200D01*
X-1105900Y-457200D01*
X-1102200Y-456700D01*
X-1099600Y-457300D01*
X-1097000Y-458400D01*
X-1095500Y-459500D01*
X-1094600Y-461900D01*
X-1094500Y-463900D01*
X-1098800Y-465200D01*
X-1098600Y-464000D01*
X-1095100Y-463100D01*
X-1095300Y-462000D01*
X-1098500Y-463000D01*
X-1098600Y-461700D01*
X-1095600Y-461300D01*
X-1095900Y-460200D01*
X-1098400Y-460700D01*
X-1098900Y-459900D01*
X-1096600Y-459400D01*
X-1097100Y-458900D01*
X-1099400Y-459000D01*
X-1098800Y-458500D01*
X-1100600Y-458000D01*
X-1102400Y-457400D01*
X-1104200Y-457500D01*
X-1106200Y-458100D01*
X-1107900Y-459000D01*
X-1110500Y-462200D01*
X-1111800Y-464800D01*
Y-467700D01*
X-1110700Y-470300D01*
X-1108700Y-472000D01*
X-1106600Y-471900D01*
X-1107900Y-470300D01*
X-1108900Y-468700D01*
Y-465500D01*
X-1107900Y-462300D01*
X-1106500Y-459900D01*
X-1104100Y-458200D01*
X-1108000Y-460000D01*
X-1108100Y-461500D01*
X-1108700Y-461200D01*
X-1110300Y-463600D01*
X-1111000Y-466000D01*
X-1110700Y-468100D01*
X-1109500Y-470600D01*
X-1107700Y-471400D01*
X-1109300Y-469100D01*
X-1109800Y-467600D01*
X-1108600Y-462200D01*
X-1110400Y-466800D01*
G01X-1113600Y-460900D02*
X-1112100Y-459000D01*
G01X-1093100Y-469400D02*
X-1087900Y-469700D01*
X-1086500Y-471400D01*
X-1083400Y-472300D01*
X-1081000Y-472000D01*
X-1079300Y-470600D01*
X-1079000Y-468900D01*
X-1079500Y-467700D01*
X-1080300Y-466600D01*
X-1081800Y-466000D01*
X-1083300Y-465500D01*
X-1085300Y-465000D01*
X-1087900Y-464000D01*
X-1089100Y-463200D01*
X-1089800Y-461000D01*
X-1089500Y-459000D01*
X-1088600Y-457700D01*
X-1086500Y-456700D01*
X-1084600Y-456100D01*
X-1081900Y-455900D01*
X-1079900Y-455800D01*
X-1076900Y-456300D01*
X-1075000Y-457000D01*
X-1073700Y-458000D01*
X-1073300Y-459400D01*
X-1077600Y-459500D01*
X-1078100Y-458800D01*
X-1074300Y-458500D01*
X-1074600Y-457800D01*
X-1078200Y-458200D01*
X-1076000Y-457400D01*
X-1079100Y-457700D01*
X-1077100Y-456900D01*
X-1080100Y-457300D01*
X-1079200Y-456600D01*
X-1083100Y-456800D01*
X-1080600Y-457300D01*
X-1083400Y-457700D01*
X-1083600Y-457000D01*
X-1087900Y-458400D01*
X-1084000Y-458100D01*
X-1088600Y-459100D01*
X-1088800Y-461500D01*
X-1087700Y-463600D01*
X-1084400Y-464300D01*
X-1081200Y-465400D01*
X-1078800Y-467300D01*
X-1078300Y-470500D01*
X-1079900Y-472600D01*
X-1083500Y-473300D01*
X-1085600Y-472600D01*
X-1088800Y-470500D01*
X-1092600Y-470200D01*
X-1092100Y-471800D01*
X-1091700Y-471300D01*
X-1089300Y-471500D01*
X-1091300Y-472300D01*
X-1088700Y-471600D01*
X-1084000Y-473500D01*
X-1089100D01*
X-1091000Y-472900D01*
X-1087200Y-472800D01*
X-1082700Y-473700D01*
X-1079000Y-473600D01*
X-1076500Y-472300D01*
X-1074700Y-470600D01*
X-1074300Y-467300D01*
X-1074800Y-465300D01*
X-1078800Y-463600D01*
X-1081600Y-462900D01*
X-1083400Y-462500D01*
X-1084800Y-461500D01*
X-1085000Y-458900D01*
X-1088100Y-459800D01*
X-1087200Y-462700D01*
X-1085000Y-463400D01*
X-1082000Y-464100D01*
X-1079600Y-465100D01*
X-1078200Y-466500D01*
X-1077700Y-468500D01*
X-1077500Y-470100D01*
X-1079200Y-472800D01*
X-1076800Y-471400D01*
X-1075300Y-470000D01*
X-1077300Y-470900D01*
X-1075000Y-468800D01*
X-1075200Y-466100D01*
X-1082700Y-462700D01*
X-1084200Y-462900D01*
X-1086600Y-461800D01*
X-1087200Y-460300D01*
X-1085800Y-459800D01*
X-1086600Y-461000D01*
X-1085300Y-460400D01*
X-1085600Y-461400D01*
X-1076700Y-466500D01*
X-1075900Y-467100D01*
X-1075700Y-468400D01*
X-1076800Y-469500D01*
X-1077800Y-466200D01*
X-1075900Y-468800D01*
G01X-1093780Y-468700D02*
X-1087100D01*
Y-469740D01*
X-1086800Y-470060D01*
X-1086520Y-470600D01*
X-1085820Y-470820D01*
X-1085660Y-471000D01*
X-1085120Y-471260D01*
X-1084400Y-471500D01*
X-1082360D01*
X-1080540Y-470600D01*
X-1080100Y-470140D01*
Y-469780D01*
X-1079840Y-469380D01*
X-1080380Y-467740D01*
X-1081440Y-466940D01*
X-1082560Y-466720D01*
X-1085740Y-465920D01*
X-1086940Y-465520D01*
X-1087600Y-465360D01*
X-1087740Y-465200D01*
X-1088540Y-464800D01*
X-1089140Y-464200D01*
X-1089540Y-464000D01*
X-1089800Y-463740D01*
X-1090000Y-463340D01*
X-1090180Y-463180D01*
X-1090500Y-462200D01*
Y-459800D01*
X-1090320Y-459260D01*
X-1090140Y-458500D01*
X-1090000Y-458260D01*
X-1089000Y-457260D01*
X-1088860Y-456940D01*
X-1085920Y-455480D01*
X-1083620Y-455100D01*
X-1082060Y-454900D01*
X-1080520D01*
X-1078580Y-455100D01*
X-1076240Y-455480D01*
X-1075120Y-455860D01*
X-1074800Y-456020D01*
X-1073680Y-456760D01*
X-1073160Y-457300D01*
X-1072620Y-458020D01*
X-1072500Y-458240D01*
Y-460300D01*
X-1078500D01*
Y-459200D01*
X-1079580Y-458380D01*
X-1080160Y-458100D01*
X-1082380D01*
X-1083280Y-458360D01*
X-1084020Y-458940D01*
X-1084340Y-459900D01*
X-1084060Y-460720D01*
X-1083740Y-461340D01*
X-1081860Y-462280D01*
X-1079400Y-462500D01*
X-1078660Y-462680D01*
X-1078100Y-462860D01*
X-1076500Y-463460D01*
X-1075320Y-463860D01*
X-1075060Y-464000D01*
X-1073820Y-465220D01*
X-1073480Y-466260D01*
X-1073300Y-467160D01*
Y-468420D01*
X-1073860Y-470700D01*
X-1074000Y-470960D01*
X-1075140Y-472300D01*
X-1075280Y-472440D01*
X-1076600Y-473380D01*
X-1077320Y-473740D01*
X-1079600Y-474500D01*
X-1088240D01*
X-1089160Y-474320D01*
X-1089920Y-474120D01*
X-1090860Y-473760D01*
X-1091560Y-473400D01*
X-1092700Y-472460D01*
X-1093180Y-471980D01*
X-1093340Y-471480D01*
X-1093520Y-471100D01*
X-1093700Y-470320D01*
X-1093780Y-468700D01*
G01X-1095100D02*
X-1092800D01*
G01X-1058300Y-469400D02*
X-1055400Y-467100D01*
X-1053900Y-463700D01*
X-1054400Y-461200D01*
X-1055900Y-459900D01*
X-1054800Y-463500D01*
X-1055400Y-463600D01*
X-1054600Y-464500D01*
X-1055700D01*
X-1055400Y-465300D01*
X-1056200Y-466800D01*
G01X-1059300Y-457700D02*
X-1059100Y-455600D01*
X-1055200Y-456300D01*
X-1052700Y-457900D01*
X-1051100Y-460800D01*
X-1050900Y-465200D01*
X-1052900Y-469400D01*
X-1055300Y-471900D01*
X-1059000Y-473500D01*
X-1066000D01*
X-1068000Y-471900D01*
X-1070200Y-468700D01*
X-1070600Y-464500D01*
X-1069000Y-460500D01*
X-1066000Y-457500D01*
X-1063000Y-456500D01*
X-1059200Y-456000D01*
X-1053000Y-458500D01*
X-1052000Y-461500D01*
Y-465700D01*
X-1053400Y-468600D01*
X-1055700Y-471000D01*
X-1058900Y-472600D01*
X-1063700Y-473000D01*
X-1065900Y-473600D01*
X-1068300Y-472900D01*
X-1070600Y-469300D01*
X-1065100Y-472600D01*
X-1060800Y-472200D01*
X-1057200Y-470700D01*
X-1055200Y-469100D01*
X-1053300Y-466500D01*
X-1052500Y-463400D01*
X-1052900Y-460100D01*
X-1057000Y-457400D01*
X-1058700Y-457200D01*
X-1057000Y-458500D01*
X-1055100Y-459800D01*
X-1053800Y-460900D01*
X-1053400Y-463100D01*
X-1053600Y-465600D01*
X-1054800Y-467500D01*
X-1056400Y-469200D01*
X-1058500Y-470200D01*
X-1060200Y-470700D01*
X-1061500Y-471400D01*
X-1063300Y-471600D01*
X-1065400Y-471500D01*
X-1069000Y-469300D01*
X-1069600Y-466400D01*
X-1069700Y-463700D01*
X-1068600Y-461200D01*
X-1066700Y-459200D01*
X-1063900Y-457600D01*
X-1061100Y-457000D01*
X-1059600D01*
X-1060200Y-457500D01*
X-1063300Y-458000D01*
X-1065300Y-459500D01*
X-1066900Y-460600D01*
X-1067900Y-462100D01*
X-1068800Y-464300D01*
X-1068700Y-466900D01*
X-1068200Y-469100D01*
X-1066900Y-470200D01*
X-1064300Y-470900D01*
X-1065700Y-469300D01*
X-1065800Y-465900D01*
X-1065300Y-462900D01*
X-1061200Y-458200D01*
X-1063600Y-458900D01*
X-1066400Y-461300D01*
X-1067800Y-464200D01*
Y-467200D01*
X-1067400Y-469300D01*
X-1066300Y-469700D01*
X-1067100Y-466400D01*
X-1066600Y-463400D01*
X-1064700Y-460000D01*
X-1062600Y-458800D01*
X-1065300Y-461700D01*
X-1066700Y-467400D01*
G01X-1060840Y-455100D02*
X-1057160D01*
X-1055260Y-455480D01*
X-1054740Y-455640D01*
X-1053380Y-456420D01*
X-1052660Y-456800D01*
X-1052020Y-457420D01*
X-1051820Y-458020D01*
X-1051200Y-458660D01*
X-1051000Y-459060D01*
X-1050840Y-459200D01*
X-1050700Y-459780D01*
Y-460140D01*
X-1050400Y-460460D01*
X-1050280Y-460680D01*
X-1050100Y-461740D01*
Y-464240D01*
X-1050280Y-465160D01*
X-1050480Y-465980D01*
X-1050680Y-467120D01*
X-1051220Y-468180D01*
X-1051840Y-469020D01*
X-1052040Y-469600D01*
X-1052740Y-470500D01*
X-1054480Y-472240D01*
X-1055000Y-472580D01*
X-1055420Y-472780D01*
X-1056220Y-473380D01*
X-1056920Y-473740D01*
X-1059380Y-474500D01*
X-1065600D01*
X-1067860Y-473740D01*
X-1068160Y-473600D01*
X-1069500Y-472460D01*
X-1069820Y-472120D01*
X-1070380Y-471200D01*
X-1071140Y-469860D01*
X-1071300Y-469400D01*
Y-464580D01*
X-1071120Y-463880D01*
X-1070740Y-462900D01*
X-1070540Y-462320D01*
X-1069980Y-461000D01*
X-1068840Y-459500D01*
X-1066900Y-457560D01*
X-1066180Y-457020D01*
X-1065400Y-456620D01*
X-1064440Y-456040D01*
X-1063500Y-455660D01*
X-1062940Y-455480D01*
X-1060840Y-455100D01*
G01X-1057800Y-458580D02*
X-1057000Y-459120D01*
X-1056760Y-459840D01*
X-1056340Y-460460D01*
X-1056100Y-461640D01*
Y-463760D01*
X-1056320Y-464860D01*
X-1056720Y-466060D01*
X-1056940Y-466920D01*
X-1057200Y-467460D01*
X-1057640Y-467880D01*
X-1058040Y-468480D01*
X-1059960Y-470420D01*
X-1061020Y-470840D01*
X-1061420Y-471100D01*
X-1062720D01*
X-1063340Y-470840D01*
X-1063860Y-470600D01*
X-1064360Y-470080D01*
X-1064820Y-469400D01*
X-1065100Y-468840D01*
Y-464920D01*
X-1064880Y-464120D01*
X-1064420Y-462780D01*
X-1064160Y-462520D01*
X-1063620Y-461700D01*
X-1063200Y-460840D01*
X-1062500Y-460140D01*
X-1062120Y-459860D01*
X-1061720Y-459360D01*
X-1060600Y-458580D01*
X-1060040Y-458300D01*
X-1058360D01*
X-1057800Y-458580D01*
G01X-1040300Y-459100D02*
X-1041400Y-464800D01*
G01X-1044800Y-458200D02*
X-1041400D01*
X-1044300Y-472700D01*
X-1047400Y-472300D01*
X-1044100Y-458800D01*
X-1042400Y-459100D01*
X-1045100Y-471900D01*
X-1046500D01*
X-1043400Y-459700D01*
X-1045600Y-471500D01*
G01X-1036600Y-449900D02*
X-1036800Y-451300D01*
X-1038600Y-452400D01*
X-1039800Y-456100D01*
X-1033700Y-456500D01*
X-1032300Y-452100D01*
X-1028400Y-452000D01*
X-1028900Y-455400D01*
X-1027200Y-456600D01*
X-1025900Y-456800D01*
X-1026200Y-458200D01*
X-1030000Y-458400D01*
X-1031800Y-468900D01*
X-1030400Y-471700D01*
X-1029400D01*
X-1029600Y-473300D01*
X-1033100Y-473400D01*
X-1036100Y-472800D01*
X-1036200Y-470500D01*
X-1035900Y-467100D01*
X-1034400Y-461400D01*
X-1033800Y-458800D01*
X-1033500Y-458400D01*
X-1035000Y-458200D01*
X-1039600D01*
X-1040800Y-458300D01*
X-1043600Y-473200D01*
X-1048000Y-473000D01*
X-1045100Y-459400D01*
X-1044900Y-458400D01*
X-1048700D01*
X-1048100Y-456600D01*
X-1044900Y-456400D01*
X-1045200Y-457700D01*
X-1047600Y-457500D01*
X-1026500D01*
G01X-1049580Y-459100D02*
X-1048740Y-455700D01*
X-1044900D01*
Y-454780D01*
X-1044720Y-454060D01*
X-1044340Y-452920D01*
X-1043940Y-452120D01*
X-1043740Y-451520D01*
X-1043600Y-451260D01*
X-1042340Y-450000D01*
X-1042080Y-449860D01*
X-1040580Y-449480D01*
X-1039440Y-449300D01*
X-1036140D01*
X-1035440Y-449400D01*
X-1035480Y-449540D01*
X-1035680Y-450360D01*
X-1035880Y-451280D01*
X-1036000Y-451900D01*
X-1036740D01*
X-1037060Y-452200D01*
X-1037860Y-452600D01*
X-1038220Y-452980D01*
X-1038480Y-453740D01*
X-1038960Y-455700D01*
X-1034020D01*
X-1033720Y-455080D01*
X-1033500Y-453400D01*
X-1032940Y-451100D01*
X-1027260D01*
X-1027280Y-451180D01*
X-1027480Y-452780D01*
X-1027860Y-454280D01*
X-1028100Y-454760D01*
Y-455700D01*
X-1024800D01*
X-1024880Y-455940D01*
X-1025080Y-456940D01*
X-1025280Y-457540D01*
X-1025480Y-458560D01*
X-1025620Y-459100D01*
X-1029100D01*
Y-460000D01*
X-1029280Y-460540D01*
X-1029480Y-461540D01*
X-1029680Y-462140D01*
X-1029880Y-462960D01*
X-1030100Y-464000D01*
X-1030280Y-465560D01*
X-1030480Y-466140D01*
X-1030680Y-467140D01*
X-1030880Y-467740D01*
X-1031040Y-468400D01*
X-1031300Y-468660D01*
Y-469800D01*
X-1030300Y-470560D01*
X-1029940Y-470900D01*
X-1028220D01*
X-1028680Y-472780D01*
X-1028880Y-474120D01*
Y-474140D01*
X-1030720Y-474300D01*
X-1032860D01*
X-1034380Y-474120D01*
X-1035860Y-473740D01*
X-1036640Y-473280D01*
X-1036960Y-472660D01*
X-1037100Y-472280D01*
Y-470160D01*
X-1036920Y-469260D01*
X-1036700Y-468640D01*
X-1036500Y-466840D01*
X-1036320Y-466260D01*
X-1036120Y-465260D01*
X-1035920Y-464660D01*
X-1035720Y-463660D01*
X-1035520Y-463060D01*
X-1035320Y-462060D01*
X-1035120Y-461440D01*
X-1034820Y-459100D01*
X-1039900D01*
Y-460220D01*
X-1040280Y-461780D01*
X-1040480Y-463380D01*
X-1041280Y-466540D01*
X-1041480Y-467140D01*
X-1041700Y-468200D01*
X-1041880Y-469760D01*
X-1042080Y-470340D01*
X-1042280Y-471360D01*
X-1042480Y-472140D01*
X-1042680Y-472740D01*
X-1042880Y-473740D01*
X-1042940Y-473900D01*
X-1049140D01*
X-1048300Y-470620D01*
X-1048100Y-469020D01*
X-1047920Y-468260D01*
X-1047720Y-467660D01*
X-1047520Y-466660D01*
X-1047320Y-466060D01*
X-1047120Y-465060D01*
X-1046920Y-464460D01*
X-1046700Y-463400D01*
X-1046500Y-462020D01*
X-1046140Y-460500D01*
X-1045900Y-460040D01*
Y-459100D01*
X-1049580D01*
G01X-1038400Y-451100D02*
X-1040600Y-455800D01*
X-1043300D01*
X-1041400Y-451300D01*
X-1038900Y-451000D01*
X-1041200Y-455000D01*
X-1042000Y-455100D01*
X-1040500Y-452000D01*
G01X-1037500Y-449800D02*
X-1037800Y-451000D01*
X-1038500Y-450100D01*
X-1042000Y-450700D01*
X-1043100Y-452300D01*
X-1044100Y-455100D01*
X-1044200Y-456600D01*
X-1036600Y-456800D01*
G01X-1031100Y-472500D02*
X-1031400Y-470900D01*
X-1031900Y-472200D01*
X-1035200D01*
Y-467600D01*
X-1032000Y-453700D01*
X-1030500Y-453800D01*
X-1030000Y-456700D01*
X-1033400Y-471900D01*
X-1034300Y-471600D01*
X-1034200Y-467100D01*
X-1031400Y-454500D01*
X-1030700Y-456500D01*
X-1033700Y-470600D01*
X-1032700Y-461100D01*
G01X-1032000Y-452900D02*
X-1029300D01*
X-1028000Y-457000D01*
X-1029500Y-453600D01*
X-1029100Y-457300D01*
X-1032800Y-472800D01*
X-1030200Y-472600D01*
G54D24*
X-1356889Y-145000D03*
X-1051613D03*
X-486810D03*
X-181534D03*
G54D33*
X-1141240Y-142362D03*
Y-102992D03*
Y-63622D03*
Y-24252D03*
X-1128760Y-83307D03*
X-1118917Y-4567D03*
X-1107500Y-83307D03*
X-1085138Y-122677D03*
Y-83307D03*
Y-43937D03*
Y-4567D03*
X-785200Y-83100D03*
X-271161Y-142362D03*
Y-102992D03*
Y-63622D03*
Y-24252D03*
X-258681Y-83307D03*
X-237421D03*
X-248839Y-4567D03*
X-215059Y-122677D03*
Y-83307D03*
Y-43937D03*
Y-4567D03*
G54D15*
X-1615984Y-173071D03*
Y-178583D03*
Y-167559D03*
X-1608110Y-172677D03*
Y-178189D03*
Y-167165D03*
X-1615984Y-162047D03*
Y-151024D03*
Y-156535D03*
X-1608110Y-161654D03*
Y-150630D03*
Y-156142D03*
X-1615984Y-134488D03*
Y-140000D03*
Y-145512D03*
X-1608110Y-134094D03*
Y-139606D03*
Y-145118D03*
X-1615984Y-128976D03*
Y-123465D03*
Y-117953D03*
X-1608110Y-128583D03*
Y-123071D03*
Y-117559D03*
X-1615984Y-112441D03*
Y-106929D03*
Y-101417D03*
X-1608110Y-112047D03*
Y-106535D03*
Y-101024D03*
X-1615984Y-95906D03*
X-1600236Y-167559D03*
X-1592362Y-167165D03*
X-1600236Y-173071D03*
X-1592362Y-172677D03*
X-1600236Y-178583D03*
X-1592362Y-178189D03*
X-1600236Y-151024D03*
X-1592362Y-150630D03*
X-1600236Y-156535D03*
X-1592362Y-156142D03*
X-1600236Y-162047D03*
X-1592362Y-161654D03*
X-1600236Y-134488D03*
X-1592362Y-134094D03*
X-1600236Y-140000D03*
X-1592362Y-139606D03*
X-1600236Y-145512D03*
X-1592362Y-145118D03*
X-1600236Y-128976D03*
Y-117953D03*
Y-123465D03*
X-1592362Y-128583D03*
Y-117559D03*
Y-123071D03*
X-1600236Y-101417D03*
Y-106929D03*
Y-112441D03*
X-1592362Y-101024D03*
Y-106535D03*
Y-112047D03*
X-1600236Y-95906D03*
X-1584488Y-167559D03*
X-1576614Y-167165D03*
X-1584488Y-173071D03*
X-1576614Y-172677D03*
X-1584488Y-178583D03*
X-1576614Y-178189D03*
X-1584488Y-151024D03*
X-1576614Y-150630D03*
X-1584488Y-156535D03*
X-1576614Y-156142D03*
X-1584488Y-162047D03*
X-1576614Y-161654D03*
X-1584488Y-134488D03*
X-1576614Y-134094D03*
X-1584488Y-140000D03*
X-1576614Y-139606D03*
X-1584488Y-145512D03*
X-1576614Y-145118D03*
X-1584488Y-128976D03*
X-1576614Y-128583D03*
X-1584488Y-117953D03*
X-1576614Y-117559D03*
X-1584488Y-123465D03*
X-1576614Y-123071D03*
X-1584488Y-101417D03*
X-1576614Y-101024D03*
X-1584488Y-106929D03*
X-1576614Y-106535D03*
X-1584488Y-112441D03*
X-1576614Y-112047D03*
X-1584488Y-95906D03*
X-1568740Y-167559D03*
X-1560866Y-167165D03*
X-1568740Y-173071D03*
X-1560866Y-172677D03*
X-1568740Y-178583D03*
X-1560866Y-178189D03*
X-1568740Y-151024D03*
X-1560866Y-150630D03*
X-1568740Y-156535D03*
X-1560866Y-156142D03*
X-1568740Y-162047D03*
X-1560866Y-161654D03*
X-1568740Y-134488D03*
X-1560866Y-134094D03*
X-1568740Y-140000D03*
X-1560866Y-139606D03*
X-1568740Y-145512D03*
X-1560866Y-145118D03*
X-1568740Y-128976D03*
Y-117953D03*
Y-123465D03*
X-1560866Y-128583D03*
Y-117559D03*
Y-123071D03*
X-1568740Y-101417D03*
Y-106929D03*
Y-112441D03*
X-1560866Y-101024D03*
Y-106535D03*
Y-112047D03*
X-1568740Y-95906D03*
X-1552992Y-167559D03*
X-1545118Y-167165D03*
X-1552992Y-173071D03*
X-1545118Y-172677D03*
X-1552992Y-178583D03*
Y-151024D03*
X-1545118Y-150630D03*
X-1552992Y-156535D03*
X-1545118Y-156142D03*
X-1552992Y-162047D03*
X-1545118Y-161654D03*
X-1552992Y-134488D03*
X-1545118Y-134094D03*
X-1552992Y-140000D03*
X-1545118Y-139606D03*
X-1552992Y-145512D03*
X-1545118Y-145118D03*
X-1552992Y-128976D03*
Y-117953D03*
Y-123465D03*
X-1545118Y-128583D03*
Y-117559D03*
Y-123071D03*
X-1552992Y-101417D03*
Y-106929D03*
Y-112441D03*
X-1545118Y-101024D03*
Y-106535D03*
Y-112047D03*
X-1552992Y-95906D03*
X-1197008Y-167953D03*
X-1189134Y-167559D03*
X-1197008Y-173465D03*
X-1189134Y-173071D03*
X-1197008Y-178976D03*
X-1189134Y-178583D03*
X-1197008Y-151417D03*
X-1189134Y-151024D03*
X-1197008Y-156929D03*
X-1189134Y-156535D03*
X-1197008Y-162441D03*
X-1189134Y-162047D03*
X-1197008Y-134882D03*
X-1189134Y-134488D03*
X-1197008Y-140394D03*
X-1189134Y-140000D03*
X-1197008Y-145906D03*
X-1189134Y-145512D03*
X-1197008Y-129370D03*
X-1181260Y-167953D03*
X-1173386Y-167559D03*
X-1181260Y-173465D03*
X-1173386Y-173071D03*
X-1181260Y-178976D03*
X-1173386Y-178583D03*
X-1181260Y-151417D03*
X-1173386Y-151024D03*
X-1181260Y-156929D03*
X-1173386Y-156535D03*
X-1181260Y-162441D03*
X-1173386Y-162047D03*
X-1181260Y-134882D03*
X-1173386Y-134488D03*
X-1181260Y-140394D03*
X-1173386Y-140000D03*
X-1181260Y-145906D03*
X-1173386Y-145512D03*
X-1181260Y-129370D03*
X-1165512Y-167953D03*
X-1157638Y-167559D03*
X-1165512Y-173465D03*
X-1157638Y-173071D03*
X-1165512Y-178976D03*
X-1157638Y-178583D03*
X-1165512Y-151417D03*
X-1157638Y-151024D03*
X-1165512Y-156929D03*
X-1157638Y-156535D03*
X-1165512Y-162441D03*
X-1157638Y-162047D03*
X-1165512Y-134882D03*
X-1157638Y-134488D03*
X-1165512Y-140394D03*
X-1157638Y-140000D03*
X-1165512Y-145906D03*
X-1157638Y-145512D03*
X-1165512Y-129370D03*
X-1014488Y-167953D03*
Y-173465D03*
Y-178976D03*
Y-151417D03*
Y-156929D03*
Y-162441D03*
Y-134882D03*
Y-140394D03*
Y-145906D03*
Y-129370D03*
X-1006614Y-167559D03*
X-998740Y-167953D03*
X-1006614Y-173071D03*
X-998740Y-173465D03*
X-1006614Y-178583D03*
X-998740Y-178976D03*
X-1006614Y-151024D03*
X-998740Y-151417D03*
X-1006614Y-156535D03*
X-998740Y-156929D03*
X-1006614Y-162047D03*
X-998740Y-162441D03*
X-1006614Y-134488D03*
X-998740Y-134882D03*
X-1006614Y-140000D03*
X-998740Y-140394D03*
X-1006614Y-145512D03*
X-998740Y-145906D03*
Y-129370D03*
X-990866Y-167559D03*
X-982992Y-167953D03*
X-990866Y-173071D03*
X-982992Y-173465D03*
X-990866Y-178583D03*
X-982992Y-178976D03*
X-990866Y-151024D03*
X-982992Y-151417D03*
X-990866Y-156535D03*
X-982992Y-156929D03*
X-990866Y-162047D03*
X-982992Y-162441D03*
X-990866Y-134488D03*
X-982992Y-134882D03*
X-990866Y-140000D03*
X-982992Y-140394D03*
X-990866Y-145512D03*
X-982992Y-145906D03*
Y-129370D03*
X-975118Y-167559D03*
Y-173071D03*
Y-178583D03*
Y-151024D03*
Y-156535D03*
Y-162047D03*
Y-134488D03*
Y-140000D03*
Y-145512D03*
X-745906Y-173071D03*
Y-178583D03*
Y-167559D03*
Y-162047D03*
Y-151024D03*
Y-156535D03*
Y-134488D03*
Y-140000D03*
Y-145512D03*
Y-128976D03*
Y-123465D03*
Y-117953D03*
Y-112441D03*
Y-106929D03*
Y-101417D03*
Y-95906D03*
X-738032Y-172677D03*
Y-178189D03*
Y-167165D03*
X-730157Y-167559D03*
Y-173071D03*
Y-178583D03*
X-738032Y-161654D03*
Y-150630D03*
Y-156142D03*
X-730157Y-151024D03*
Y-156535D03*
Y-162047D03*
X-738032Y-134094D03*
Y-139606D03*
Y-145118D03*
X-730157Y-134488D03*
Y-140000D03*
Y-145512D03*
Y-128976D03*
X-738032Y-128583D03*
X-730157Y-117953D03*
Y-123465D03*
X-738032Y-123071D03*
Y-117559D03*
X-730157Y-101417D03*
Y-106929D03*
Y-112441D03*
X-738032Y-112047D03*
Y-106535D03*
Y-101024D03*
X-730157Y-95906D03*
X-722283Y-167165D03*
X-714409Y-167559D03*
X-722283Y-172677D03*
X-714409Y-173071D03*
X-722283Y-178189D03*
X-714409Y-178583D03*
X-722283Y-150630D03*
X-714409Y-151024D03*
X-722283Y-156142D03*
X-714409Y-156535D03*
X-722283Y-161654D03*
X-714409Y-162047D03*
X-722283Y-134094D03*
X-714409Y-134488D03*
X-722283Y-139606D03*
X-714409Y-140000D03*
X-722283Y-145118D03*
X-714409Y-145512D03*
X-722283Y-128583D03*
Y-117559D03*
Y-123071D03*
X-714409Y-128976D03*
Y-117953D03*
Y-123465D03*
X-722283Y-101024D03*
Y-106535D03*
Y-112047D03*
X-714409Y-101417D03*
Y-106929D03*
Y-112441D03*
Y-95906D03*
X-706535Y-167165D03*
X-698661Y-167559D03*
X-706535Y-172677D03*
X-698661Y-173071D03*
X-706535Y-178189D03*
X-698661Y-178583D03*
X-706535Y-150630D03*
X-698661Y-151024D03*
X-706535Y-156142D03*
X-698661Y-156535D03*
X-706535Y-161654D03*
X-698661Y-162047D03*
X-706535Y-134094D03*
X-698661Y-134488D03*
X-706535Y-139606D03*
X-698661Y-140000D03*
X-706535Y-145118D03*
X-698661Y-145512D03*
X-706535Y-128583D03*
Y-117559D03*
Y-123071D03*
X-698661Y-128976D03*
Y-117953D03*
Y-123465D03*
X-706535Y-101024D03*
Y-106535D03*
Y-112047D03*
X-698661Y-101417D03*
Y-106929D03*
Y-112441D03*
Y-95906D03*
X-690787Y-167165D03*
X-682913Y-167559D03*
X-690787Y-172677D03*
X-682913Y-173071D03*
X-690787Y-178189D03*
X-682913Y-178583D03*
X-690787Y-150630D03*
X-682913Y-151024D03*
X-690787Y-156142D03*
X-682913Y-156535D03*
X-690787Y-161654D03*
X-682913Y-162047D03*
X-690787Y-134094D03*
X-682913Y-134488D03*
X-690787Y-139606D03*
X-682913Y-140000D03*
X-690787Y-145118D03*
X-682913Y-145512D03*
X-690787Y-128583D03*
X-682913Y-128976D03*
X-690787Y-117559D03*
X-682913Y-117953D03*
X-690787Y-123071D03*
X-682913Y-123465D03*
X-690787Y-101024D03*
X-682913Y-101417D03*
X-690787Y-106535D03*
X-682913Y-106929D03*
X-690787Y-112047D03*
X-682913Y-112441D03*
Y-95906D03*
X-675039Y-167165D03*
Y-172677D03*
Y-150630D03*
Y-156142D03*
Y-161654D03*
Y-134094D03*
Y-139606D03*
Y-145118D03*
Y-128583D03*
Y-117559D03*
Y-123071D03*
Y-101024D03*
Y-106535D03*
Y-112047D03*
X-326929Y-167953D03*
X-319055Y-167559D03*
X-326929Y-173465D03*
X-319055Y-173071D03*
X-326929Y-178976D03*
X-319055Y-178583D03*
X-326929Y-151417D03*
X-319055Y-151024D03*
X-326929Y-156929D03*
X-319055Y-156535D03*
X-326929Y-162441D03*
X-319055Y-162047D03*
X-326929Y-134882D03*
X-319055Y-134488D03*
X-326929Y-140394D03*
X-319055Y-140000D03*
X-326929Y-145906D03*
X-319055Y-145512D03*
X-326929Y-129370D03*
X-311181Y-167953D03*
X-303307Y-167559D03*
X-311181Y-173465D03*
X-303307Y-173071D03*
X-311181Y-178976D03*
X-303307Y-178583D03*
X-311181Y-151417D03*
X-303307Y-151024D03*
X-311181Y-156929D03*
X-303307Y-156535D03*
X-311181Y-162441D03*
X-303307Y-162047D03*
X-311181Y-134882D03*
X-303307Y-134488D03*
X-311181Y-140394D03*
X-303307Y-140000D03*
X-311181Y-145906D03*
X-303307Y-145512D03*
X-311181Y-129370D03*
X-295433Y-167953D03*
X-287559Y-167559D03*
X-295433Y-173465D03*
X-287559Y-173071D03*
X-295433Y-178976D03*
X-287559Y-178583D03*
X-295433Y-151417D03*
X-287559Y-151024D03*
X-295433Y-156929D03*
X-287559Y-156535D03*
X-295433Y-162441D03*
X-287559Y-162047D03*
X-295433Y-134882D03*
X-287559Y-134488D03*
X-295433Y-140394D03*
X-287559Y-140000D03*
X-295433Y-145906D03*
X-287559Y-145512D03*
X-295433Y-129370D03*
X-144409Y-167953D03*
Y-173465D03*
Y-178976D03*
Y-151417D03*
Y-156929D03*
Y-162441D03*
Y-134882D03*
Y-140394D03*
Y-145906D03*
Y-129370D03*
X-136535Y-167559D03*
X-128661Y-167953D03*
X-136535Y-173071D03*
X-128661Y-173465D03*
X-136535Y-178583D03*
X-128661Y-178976D03*
X-136535Y-151024D03*
X-128661Y-151417D03*
X-136535Y-156535D03*
X-128661Y-156929D03*
X-136535Y-162047D03*
X-128661Y-162441D03*
X-136535Y-134488D03*
X-128661Y-134882D03*
X-136535Y-140000D03*
X-128661Y-140394D03*
X-136535Y-145512D03*
X-128661Y-145906D03*
Y-129370D03*
X-120787Y-167559D03*
X-112913Y-167953D03*
X-120787Y-173071D03*
X-112913Y-173465D03*
X-120787Y-178583D03*
X-112913Y-178976D03*
X-120787Y-151024D03*
X-112913Y-151417D03*
X-120787Y-156535D03*
X-112913Y-156929D03*
X-120787Y-162047D03*
X-112913Y-162441D03*
X-120787Y-134488D03*
X-112913Y-134882D03*
X-120787Y-140000D03*
X-112913Y-140394D03*
X-120787Y-145512D03*
X-112913Y-145906D03*
Y-129370D03*
X-105039Y-167559D03*
Y-173071D03*
Y-178583D03*
Y-151024D03*
Y-156535D03*
Y-162047D03*
Y-134488D03*
Y-140000D03*
Y-145512D03*
G54D43*
G01X-1183150Y-540000D02*
Y-552500D01*
G01X-1186485Y-540000D02*
X-1179815D01*
G01X-1171350Y-552500D02*
X-1172510Y-552292D01*
X-1173525Y-551459D01*
X-1174395Y-550208D01*
X-1174975Y-548750D01*
X-1175265Y-547083D01*
Y-545417D01*
X-1174975Y-543750D01*
X-1174395Y-542292D01*
X-1173525Y-541042D01*
X-1172510Y-540208D01*
X-1171350Y-540000D01*
X-1170190Y-540208D01*
X-1169175Y-541042D01*
X-1168305Y-542292D01*
X-1167725Y-543750D01*
X-1167435Y-545417D01*
Y-547083D01*
X-1167725Y-548750D01*
X-1168305Y-550208D01*
X-1169175Y-551459D01*
X-1170190Y-552292D01*
X-1171350Y-552500D01*
G01X-1162450D02*
Y-540000D01*
X-1158970D01*
X-1157810Y-540625D01*
X-1156940Y-542083D01*
X-1156650Y-543750D01*
X-1156940Y-545417D01*
X-1157665Y-546667D01*
X-1158970Y-547292D01*
X-1162450D01*
G01X-1138995Y-550834D02*
X-1137835Y-551875D01*
X-1136530Y-552500D01*
X-1135370D01*
X-1134210Y-551875D01*
X-1133340Y-550834D01*
X-1132905Y-549375D01*
X-1133195Y-547917D01*
X-1133920Y-546667D01*
X-1135225Y-545833D01*
X-1136965Y-545417D01*
X-1137980Y-544584D01*
X-1138415Y-543125D01*
X-1138125Y-541667D01*
X-1137400Y-540625D01*
X-1136385Y-540000D01*
X-1135370D01*
X-1134355Y-540417D01*
X-1133485Y-541458D01*
G01X-1125890Y-540000D02*
X-1122410D01*
G01X-1124150D02*
Y-552500D01*
G01X-1125890D02*
X-1122410D01*
G01X-1115540D02*
Y-540000D01*
X-1112640D01*
X-1111480Y-540625D01*
X-1110610Y-541458D01*
X-1109885Y-542708D01*
X-1109305Y-544167D01*
X-1109160Y-546250D01*
X-1109305Y-548333D01*
X-1109885Y-549792D01*
X-1110610Y-551042D01*
X-1111480Y-551875D01*
X-1112640Y-552500D01*
X-1115540D01*
G01X-1097650D02*
X-1103450D01*
Y-540000D01*
X-1097650D01*
G01X-1099970Y-546042D02*
X-1103450D01*
G01X-1079995Y-550834D02*
X-1078835Y-551875D01*
X-1077530Y-552500D01*
X-1076370D01*
X-1075210Y-551875D01*
X-1074340Y-550834D01*
X-1073905Y-549375D01*
X-1074195Y-547917D01*
X-1074920Y-546667D01*
X-1076225Y-545833D01*
X-1077965Y-545417D01*
X-1078980Y-544584D01*
X-1079415Y-543125D01*
X-1079125Y-541667D01*
X-1078400Y-540625D01*
X-1077385Y-540000D01*
X-1076370D01*
X-1075355Y-540417D01*
X-1074485Y-541458D01*
G01X-1065150Y-552500D02*
X-1066310Y-552292D01*
X-1067325Y-551459D01*
X-1068195Y-550208D01*
X-1068775Y-548750D01*
X-1069065Y-547083D01*
Y-545417D01*
X-1068775Y-543750D01*
X-1068195Y-542292D01*
X-1067325Y-541042D01*
X-1066310Y-540208D01*
X-1065150Y-540000D01*
X-1063990Y-540208D01*
X-1062975Y-541042D01*
X-1062105Y-542292D01*
X-1061525Y-543750D01*
X-1061235Y-545417D01*
Y-547083D01*
X-1061525Y-548750D01*
X-1062105Y-550208D01*
X-1062975Y-551459D01*
X-1063990Y-552292D01*
X-1065150Y-552500D01*
G01X-1056250Y-540000D02*
Y-552500D01*
X-1050450D01*
G01X-1044740D02*
Y-540000D01*
X-1041840D01*
X-1040680Y-540625D01*
X-1039810Y-541458D01*
X-1039085Y-542708D01*
X-1038505Y-544167D01*
X-1038360Y-546250D01*
X-1038505Y-548333D01*
X-1039085Y-549792D01*
X-1039810Y-551042D01*
X-1040680Y-551875D01*
X-1041840Y-552500D01*
X-1044740D01*
G01X-1026850D02*
X-1032650D01*
Y-540000D01*
X-1026850D01*
G01X-1029170Y-546042D02*
X-1032650D01*
G01X-1020850Y-552500D02*
Y-540000D01*
X-1017225D01*
X-1016065Y-540625D01*
X-1015340Y-541458D01*
X-1015050Y-543125D01*
X-1015340Y-544792D01*
X-1016210Y-545833D01*
X-1017225Y-546458D01*
X-1020850D01*
G01X-1017225D02*
X-1015050Y-552500D01*
G01X-1009920D02*
Y-540000D01*
X-1006150Y-550417D01*
X-1002380Y-540000D01*
Y-552500D01*
G01X-997975D02*
X-994350Y-540000D01*
X-990725Y-552500D01*
G01X-992030Y-548125D02*
X-996670D01*
G01X-985595Y-550834D02*
X-984435Y-551875D01*
X-983130Y-552500D01*
X-981970D01*
X-980810Y-551875D01*
X-979940Y-550834D01*
X-979505Y-549375D01*
X-979795Y-547917D01*
X-980520Y-546667D01*
X-981825Y-545833D01*
X-983565Y-545417D01*
X-984580Y-544584D01*
X-985015Y-543125D01*
X-984725Y-541667D01*
X-984000Y-540625D01*
X-982985Y-540000D01*
X-981970D01*
X-980955Y-540417D01*
X-980085Y-541458D01*
G01X-973940Y-552500D02*
Y-540000D01*
G01X-968430D02*
X-973940Y-547709D01*
G01X-967560Y-552500D02*
X-971475Y-544167D01*
G54D16*
X-1600709Y4685D03*
X-1560709D03*
X-1520709D03*
X-1480709D03*
G54D34*
X-1122128Y-170650D03*
Y-175150D03*
X-1121800Y-180000D03*
X-1127689Y-179900D03*
X-1131311D03*
X-1118528Y-170650D03*
Y-175150D03*
X-1118200Y-180000D03*
X-1099028Y-175150D03*
X-1102628D03*
X-1099028Y-170650D03*
X-1102628D03*
X-1099028Y-179650D03*
X-1102628D03*
X-1088489Y-179700D03*
X-1092111D03*
X-1050800Y-29400D03*
X-1047200D03*
X-1047289Y-23000D03*
X-1050911D03*
X-1050800Y-5400D03*
X-1047200D03*
X-1047189Y0D03*
X-1050811D03*
X-257889Y-180000D03*
X-261511D03*
X-252050Y-170650D03*
X-248450D03*
X-252050Y-175150D03*
X-248450D03*
X-248100Y-180000D03*
X-251700D03*
X-228950Y-175150D03*
X-232550D03*
X-228950Y-170650D03*
X-232550D03*
X-228950Y-179650D03*
X-232550D03*
X-222011Y-179900D03*
X-218389D03*
X-179950Y-29850D03*
X-176350D03*
X-176389Y-24500D03*
X-180011D03*
X-178800Y-4500D03*
X-175200D03*
X-175189Y1000D03*
X-178811D03*
G54D25*
X-1341850Y-16000D03*
X-1330350Y-6000D03*
X-1311050Y-16900D03*
X-1299550Y-6900D03*
X-471771Y-16000D03*
X-460271Y-6000D03*
X-440971Y-16900D03*
X-429471Y-6900D03*
G54D44*
G01X-1185925Y-592500D02*
X-1178575Y-577500D01*
G01X-1185925D02*
X-1178575Y-592500D01*
G01X-1168050D02*
X-1166825Y-592250D01*
X-1165425Y-591500D01*
X-1164550Y-590250D01*
X-1164200Y-588500D01*
X-1164550Y-586750D01*
X-1165600Y-585250D01*
X-1167175Y-584500D01*
X-1168925D01*
X-1169975Y-584000D01*
X-1170850Y-582750D01*
X-1171200Y-581000D01*
X-1170675Y-579250D01*
X-1169450Y-578000D01*
X-1168050Y-577500D01*
X-1166650Y-578000D01*
X-1165425Y-579250D01*
X-1164900Y-581000D01*
X-1165250Y-582750D01*
X-1166125Y-584000D01*
X-1167175Y-584500D01*
X-1168925D01*
X-1170500Y-585250D01*
X-1171550Y-586750D01*
X-1171900Y-588500D01*
X-1171550Y-590250D01*
X-1170675Y-591500D01*
X-1169275Y-592250D01*
X-1168050Y-592500D01*
G01X-1153850D02*
X-1152625Y-592250D01*
X-1151225Y-591500D01*
X-1150350Y-590250D01*
X-1150000Y-588500D01*
X-1150350Y-586750D01*
X-1151400Y-585250D01*
X-1152975Y-584500D01*
X-1154725D01*
X-1155775Y-584000D01*
X-1156650Y-582750D01*
X-1157000Y-581000D01*
X-1156475Y-579250D01*
X-1155250Y-578000D01*
X-1153850Y-577500D01*
X-1152450Y-578000D01*
X-1151225Y-579250D01*
X-1150700Y-581000D01*
X-1151050Y-582750D01*
X-1151925Y-584000D01*
X-1152975Y-584500D01*
X-1154725D01*
X-1156300Y-585250D01*
X-1157350Y-586750D01*
X-1157700Y-588500D01*
X-1157350Y-590250D01*
X-1156475Y-591500D01*
X-1155075Y-592250D01*
X-1153850Y-592500D01*
G01X-1140000D02*
X-1139650Y-589250D01*
X-1139125Y-586500D01*
X-1138425Y-584000D01*
X-1137550Y-581250D01*
X-1136150Y-577500D01*
X-1143150D01*
G01X-1129300Y-590250D02*
X-1128250Y-591500D01*
X-1127025Y-592250D01*
X-1125450Y-592500D01*
X-1123875Y-592000D01*
X-1122650Y-591000D01*
X-1121775Y-589250D01*
X-1121600Y-587250D01*
X-1121950Y-585250D01*
X-1122825Y-584000D01*
X-1124050Y-583000D01*
X-1125275Y-582750D01*
X-1126500Y-583000D01*
X-1128075Y-584000D01*
X-1127550Y-577500D01*
X-1122825D01*
G01X-1111600Y-592500D02*
X-1111250Y-589250D01*
X-1110725Y-586500D01*
X-1110025Y-584000D01*
X-1109150Y-581250D01*
X-1107750Y-577500D01*
X-1114750D01*
G01X-1097050Y-592500D02*
Y-577500D01*
X-1099150Y-580500D01*
G01Y-592500D02*
X-1094950D01*
G01X-1085125Y-587500D02*
X-1080575D01*
G01X-1068650Y-577500D02*
X-1070050Y-578000D01*
X-1071100Y-579250D01*
X-1071800Y-580750D01*
X-1072325Y-582750D01*
X-1072500Y-585000D01*
X-1072325Y-587250D01*
X-1071800Y-589250D01*
X-1071100Y-590750D01*
X-1070050Y-592000D01*
X-1068650Y-592500D01*
X-1067250Y-592000D01*
X-1066200Y-590750D01*
X-1065500Y-589250D01*
X-1064975Y-587250D01*
X-1064800Y-585000D01*
X-1064975Y-582750D01*
X-1065500Y-580750D01*
X-1066200Y-579250D01*
X-1067250Y-578000D01*
X-1068650Y-577500D01*
G01X-1054450D02*
X-1055850Y-578000D01*
X-1056900Y-579250D01*
X-1057600Y-580750D01*
X-1058125Y-582750D01*
X-1058300Y-585000D01*
X-1058125Y-587250D01*
X-1057600Y-589250D01*
X-1056900Y-590750D01*
X-1055850Y-592000D01*
X-1054450Y-592500D01*
X-1053050Y-592000D01*
X-1052000Y-590750D01*
X-1051300Y-589250D01*
X-1050775Y-587250D01*
X-1050600Y-585000D01*
X-1050775Y-582750D01*
X-1051300Y-580750D01*
X-1052000Y-579250D01*
X-1053050Y-578000D01*
X-1054450Y-577500D01*
G01X-1044100Y-590250D02*
X-1043050Y-591500D01*
X-1041825Y-592250D01*
X-1040250Y-592500D01*
X-1038675Y-592000D01*
X-1037450Y-591000D01*
X-1036575Y-589250D01*
X-1036400Y-587250D01*
X-1036750Y-585250D01*
X-1037625Y-584000D01*
X-1038850Y-583000D01*
X-1040075Y-582750D01*
X-1041300Y-583000D01*
X-1042875Y-584000D01*
X-1042350Y-577500D01*
X-1037625D01*
G01X-911875Y-592500D02*
X-907500Y-577500D01*
X-903125Y-592500D01*
G01X-904700Y-587250D02*
X-910300D01*
G54D35*
X-1120276Y-142362D03*
X-1123425D03*
X-1126575D03*
X-1128150Y-110079D03*
X-1125000D03*
X-1121850D03*
X-1104528Y-142362D03*
X-1107677D03*
X-1110827D03*
X-1113976D03*
X-1117126D03*
X-1118701Y-110079D03*
X-1115551D03*
X-1112402D03*
X-1109252D03*
X-1106102D03*
X-1098228Y-142362D03*
X-1101378D03*
X-1102953Y-110079D03*
X-1099803D03*
X-256496Y-142362D03*
X-258071Y-110079D03*
X-254921D03*
X-240748Y-142362D03*
X-243898D03*
X-247047D03*
X-250197D03*
X-253346D03*
X-251772Y-110079D03*
X-248622D03*
X-245472D03*
X-242323D03*
X-239173D03*
X-228150Y-142362D03*
X-231299D03*
X-234449D03*
X-237598D03*
X-236024Y-110079D03*
X-232874D03*
X-229724D03*
G54D26*
X-1327756Y-127795D03*
X-457677D03*
G54D17*
X-1545118Y-178189D03*
X-675039D03*
G54D45*
G01X-1200000Y-560000D02*
X-890000D01*
G01Y-520000D02*
X-1200000D01*
G01X-575000Y-480000D02*
X-1200000D01*
G01X-927500Y-560000D02*
Y-600000D01*
G01X-915000Y-440000D02*
Y-480000D01*
G01X-890000D02*
Y-600000D01*
G01X-870000Y-440000D02*
Y-480000D01*
G01X-680000D02*
Y-440000D01*
G01X-1200000Y-600000D02*
X-575000D01*
Y-440000D01*
X-1200000D01*
Y-600000D01*
G54D27*
X-1312008Y-149449D03*
X-441929D03*
G54D18*
X-1519000Y-125359D03*
Y-120241D03*
X-1396100Y-136650D03*
Y-131550D03*
X-1356500Y-16041D03*
Y-21159D03*
X-1324500Y-16841D03*
Y-21959D03*
X-1316728Y-85900D03*
Y-80800D03*
X-1317700Y-69059D03*
Y-63941D03*
X-1113328Y-179209D03*
Y-174091D03*
X-1107828D03*
Y-179209D03*
X-1061900Y-38150D03*
X-1063928Y-53400D03*
Y-48300D03*
X-1061900Y-33050D03*
X-1062000Y-9450D03*
Y-14550D03*
X-948500Y-170441D03*
Y-175559D03*
X-649700Y-125359D03*
Y-120241D03*
X-535500Y-127350D03*
Y-122250D03*
X-486421Y-16041D03*
Y-21159D03*
X-448128Y-85800D03*
Y-80700D03*
X-449100Y-63841D03*
Y-68959D03*
X-454421Y-16841D03*
Y-21959D03*
X-243250Y-179209D03*
Y-174091D03*
X-237750D03*
Y-179209D03*
X-190100Y-38450D03*
X-192350Y-52900D03*
Y-47800D03*
X-190100Y-33350D03*
X-190400Y-8750D03*
Y-13850D03*
X-78400Y-171441D03*
Y-176559D03*
G54D36*
X-1132087Y-126220D03*
X-1094291D03*
X-262008D03*
X-224213D03*
G54D46*
G01X-1007500Y-470000D02*
X-1006450Y-475000D01*
X-1005250Y-470000D01*
X-1004050Y-475000D01*
X-1003000Y-470000D01*
G01X-1001125Y-475000D02*
X-999250Y-470000D01*
X-997375Y-475000D01*
G01X-998050Y-473250D02*
X-1000450D01*
G01X-994825Y-474333D02*
X-994225Y-474750D01*
X-993550Y-475000D01*
X-992950D01*
X-992350Y-474750D01*
X-991900Y-474333D01*
X-991675Y-473750D01*
X-991825Y-473167D01*
X-992200Y-472667D01*
X-992875Y-472333D01*
X-993775Y-472167D01*
X-994300Y-471833D01*
X-994525Y-471250D01*
X-994375Y-470667D01*
X-994000Y-470250D01*
X-993475Y-470000D01*
X-992950D01*
X-992425Y-470167D01*
X-991975Y-470583D01*
G01X-988825Y-475000D02*
Y-470000D01*
G01X-985675D02*
Y-475000D01*
G01Y-472500D02*
X-988825D01*
G01X-976525Y-474417D02*
X-976000Y-474833D01*
X-975400Y-475000D01*
X-974800Y-474833D01*
X-974275Y-474333D01*
X-973900Y-473583D01*
X-973750Y-472833D01*
Y-471917D01*
X-973900Y-471167D01*
X-974275Y-470500D01*
X-974725Y-470167D01*
X-975250Y-470000D01*
X-975850Y-470167D01*
X-976300Y-470500D01*
X-976600Y-471000D01*
X-976750Y-471667D01*
X-976600Y-472250D01*
X-976225Y-472833D01*
X-975775Y-473167D01*
X-975250Y-473250D01*
X-974650Y-473083D01*
X-974200Y-472667D01*
X-973750Y-471917D01*
G01X-969250Y-475000D02*
X-968725Y-474917D01*
X-968125Y-474667D01*
X-967750Y-474250D01*
X-967600Y-473667D01*
X-967750Y-473083D01*
X-968200Y-472583D01*
X-968875Y-472333D01*
X-969625D01*
X-970075Y-472167D01*
X-970450Y-471750D01*
X-970600Y-471167D01*
X-970375Y-470583D01*
X-969850Y-470167D01*
X-969250Y-470000D01*
X-968650Y-470167D01*
X-968125Y-470583D01*
X-967900Y-471167D01*
X-968050Y-471750D01*
X-968425Y-472167D01*
X-968875Y-472333D01*
X-969625D01*
X-970300Y-472583D01*
X-970750Y-473083D01*
X-970900Y-473667D01*
X-970750Y-474250D01*
X-970375Y-474667D01*
X-969775Y-474917D01*
X-969250Y-475000D01*
G01X-963250Y-470000D02*
X-963850Y-470167D01*
X-964300Y-470583D01*
X-964600Y-471083D01*
X-964825Y-471750D01*
X-964900Y-472500D01*
X-964825Y-473250D01*
X-964600Y-473917D01*
X-964300Y-474417D01*
X-963850Y-474833D01*
X-963250Y-475000D01*
X-962650Y-474833D01*
X-962200Y-474417D01*
X-961900Y-473917D01*
X-961675Y-473250D01*
X-961600Y-472500D01*
X-961675Y-471750D01*
X-961900Y-471083D01*
X-962200Y-470583D01*
X-962650Y-470167D01*
X-963250Y-470000D01*
G01X-958900Y-474250D02*
X-958450Y-474667D01*
X-957925Y-474917D01*
X-957250Y-475000D01*
X-956575Y-474833D01*
X-956050Y-474500D01*
X-955675Y-473917D01*
X-955600Y-473250D01*
X-955750Y-472583D01*
X-956125Y-472167D01*
X-956650Y-471833D01*
X-957175Y-471750D01*
X-957700Y-471833D01*
X-958375Y-472167D01*
X-958150Y-470000D01*
X-956125D01*
G01X-952675Y-470833D02*
X-952225Y-470333D01*
X-951700Y-470083D01*
X-951100Y-470000D01*
X-950350Y-470167D01*
X-949825Y-470583D01*
X-949675Y-471083D01*
X-949750Y-471583D01*
X-950050Y-472000D01*
X-951550Y-472833D01*
X-952225Y-473417D01*
X-952675Y-474250D01*
X-952825Y-475000D01*
X-949675D01*
G01X-946225Y-473333D02*
X-944275D01*
G01X-940675Y-472917D02*
X-940150Y-472333D01*
X-939700Y-472000D01*
X-939100Y-471833D01*
X-938575Y-472000D01*
X-938200Y-472333D01*
X-937900Y-472833D01*
X-937825Y-473417D01*
X-937900Y-473917D01*
X-938200Y-474417D01*
X-938650Y-474833D01*
X-939175Y-475000D01*
X-939775Y-474833D01*
X-940300Y-474333D01*
X-940600Y-473583D01*
X-940675Y-472750D01*
X-940525Y-471667D01*
X-940300Y-471083D01*
X-939925Y-470500D01*
X-939400Y-470083D01*
X-938875Y-470000D01*
X-938350Y-470167D01*
X-937975Y-470583D01*
G01X-934900Y-474000D02*
X-934450Y-474583D01*
X-933850Y-474917D01*
X-933175Y-475000D01*
X-932575Y-474917D01*
X-931975Y-474500D01*
X-931600Y-474000D01*
X-931525Y-473500D01*
X-931675Y-472917D01*
X-932200Y-472500D01*
X-932725Y-472333D01*
X-933400D01*
G01X-932725D02*
X-932275Y-472083D01*
X-931900Y-471667D01*
X-931750Y-471167D01*
X-931900Y-470667D01*
X-932275Y-470250D01*
X-932950Y-470000D01*
X-933625Y-470083D01*
X-934300Y-470417D01*
G01X-928525Y-474417D02*
X-928000Y-474833D01*
X-927400Y-475000D01*
X-926800Y-474833D01*
X-926275Y-474333D01*
X-925900Y-473583D01*
X-925750Y-472833D01*
Y-471917D01*
X-925900Y-471167D01*
X-926275Y-470500D01*
X-926725Y-470167D01*
X-927250Y-470000D01*
X-927850Y-470167D01*
X-928300Y-470500D01*
X-928600Y-471000D01*
X-928750Y-471667D01*
X-928600Y-472250D01*
X-928225Y-472833D01*
X-927775Y-473167D01*
X-927250Y-473250D01*
X-926650Y-473083D01*
X-926200Y-472667D01*
X-925750Y-471917D01*
G01X-922525Y-474417D02*
X-922000Y-474833D01*
X-921400Y-475000D01*
X-920800Y-474833D01*
X-920275Y-474333D01*
X-919900Y-473583D01*
X-919750Y-472833D01*
Y-471917D01*
X-919900Y-471167D01*
X-920275Y-470500D01*
X-920725Y-470167D01*
X-921250Y-470000D01*
X-921850Y-470167D01*
X-922300Y-470500D01*
X-922600Y-471000D01*
X-922750Y-471667D01*
X-922600Y-472250D01*
X-922225Y-472833D01*
X-921775Y-473167D01*
X-921250Y-473250D01*
X-920650Y-473083D01*
X-920200Y-472667D01*
X-919750Y-471917D01*
G01X-1006750Y-465000D02*
Y-460000D01*
X-1004875D01*
X-1004275Y-460250D01*
X-1003900Y-460583D01*
X-1003750Y-461250D01*
X-1003900Y-461917D01*
X-1004350Y-462333D01*
X-1004875Y-462583D01*
X-1006750D01*
G01X-1004875D02*
X-1003750Y-465000D01*
G01X-997750D02*
X-1000750D01*
Y-460000D01*
X-997750D01*
G01X-998950Y-462417D02*
X-1000750D01*
G01X-994900Y-465000D02*
Y-460000D01*
X-993400D01*
X-992800Y-460250D01*
X-992350Y-460583D01*
X-991975Y-461083D01*
X-991675Y-461667D01*
X-991600Y-462500D01*
X-991675Y-463333D01*
X-991975Y-463917D01*
X-992350Y-464417D01*
X-992800Y-464750D01*
X-993400Y-465000D01*
X-994900D01*
G01X-989200D02*
Y-460000D01*
X-987250Y-464167D01*
X-985300Y-460000D01*
Y-465000D01*
G01X-981250D02*
X-981850Y-464917D01*
X-982375Y-464583D01*
X-982825Y-464083D01*
X-983125Y-463500D01*
X-983275Y-462833D01*
Y-462167D01*
X-983125Y-461500D01*
X-982825Y-460917D01*
X-982375Y-460417D01*
X-981850Y-460083D01*
X-981250Y-460000D01*
X-980650Y-460083D01*
X-980125Y-460417D01*
X-979675Y-460917D01*
X-979375Y-461500D01*
X-979225Y-462167D01*
Y-462833D01*
X-979375Y-463500D01*
X-979675Y-464083D01*
X-980125Y-464583D01*
X-980650Y-464917D01*
X-981250Y-465000D01*
G01X-976975D02*
Y-460000D01*
X-973525Y-465000D01*
Y-460000D01*
G01X-970900Y-465000D02*
Y-460000D01*
X-969400D01*
X-968800Y-460250D01*
X-968350Y-460583D01*
X-967975Y-461083D01*
X-967675Y-461667D01*
X-967600Y-462500D01*
X-967675Y-463333D01*
X-967975Y-463917D01*
X-968350Y-464417D01*
X-968800Y-464750D01*
X-969400Y-465000D01*
X-970900D01*
G01X-1005250Y-455000D02*
Y-450000D01*
X-1006150Y-451000D01*
G01Y-455000D02*
X-1004350D01*
G01X-995200D02*
Y-450000D01*
X-993250Y-454167D01*
X-991300Y-450000D01*
Y-455000D01*
G01X-988150Y-450000D02*
X-986350D01*
G01X-987250D02*
Y-455000D01*
G01X-988150D02*
X-986350D01*
G01X-979600Y-450417D02*
X-980050Y-450167D01*
X-980575Y-450000D01*
X-981175D01*
X-981850Y-450250D01*
X-982375Y-450667D01*
X-982750Y-451167D01*
X-983050Y-452000D01*
X-983125Y-452750D01*
X-982975Y-453500D01*
X-982750Y-454000D01*
X-982300Y-454500D01*
X-981775Y-454833D01*
X-981250Y-455000D01*
X-980725D01*
X-980200Y-454833D01*
X-979750Y-454583D01*
X-979375Y-454250D01*
G01X-976750Y-455000D02*
Y-450000D01*
X-974875D01*
X-974275Y-450250D01*
X-973900Y-450583D01*
X-973750Y-451250D01*
X-973900Y-451917D01*
X-974350Y-452333D01*
X-974875Y-452583D01*
X-976750D01*
G01X-974875D02*
X-973750Y-455000D01*
G01X-969250D02*
X-969850Y-454917D01*
X-970375Y-454583D01*
X-970825Y-454083D01*
X-971125Y-453500D01*
X-971275Y-452833D01*
Y-452167D01*
X-971125Y-451500D01*
X-970825Y-450917D01*
X-970375Y-450417D01*
X-969850Y-450083D01*
X-969250Y-450000D01*
X-968650Y-450083D01*
X-968125Y-450417D01*
X-967675Y-450917D01*
X-967375Y-451500D01*
X-967225Y-452167D01*
Y-452833D01*
X-967375Y-453500D01*
X-967675Y-454083D01*
X-968125Y-454583D01*
X-968650Y-454917D01*
X-969250Y-455000D01*
G01X-964825Y-454333D02*
X-964225Y-454750D01*
X-963550Y-455000D01*
X-962950D01*
X-962350Y-454750D01*
X-961900Y-454333D01*
X-961675Y-453750D01*
X-961825Y-453167D01*
X-962200Y-452667D01*
X-962875Y-452333D01*
X-963775Y-452167D01*
X-964300Y-451833D01*
X-964525Y-451250D01*
X-964375Y-450667D01*
X-964000Y-450250D01*
X-963475Y-450000D01*
X-962950D01*
X-962425Y-450167D01*
X-961975Y-450583D01*
G01X-957250Y-455000D02*
X-957850Y-454917D01*
X-958375Y-454583D01*
X-958825Y-454083D01*
X-959125Y-453500D01*
X-959275Y-452833D01*
Y-452167D01*
X-959125Y-451500D01*
X-958825Y-450917D01*
X-958375Y-450417D01*
X-957850Y-450083D01*
X-957250Y-450000D01*
X-956650Y-450083D01*
X-956125Y-450417D01*
X-955675Y-450917D01*
X-955375Y-451500D01*
X-955225Y-452167D01*
Y-452833D01*
X-955375Y-453500D01*
X-955675Y-454083D01*
X-956125Y-454583D01*
X-956650Y-454917D01*
X-957250Y-455000D01*
G01X-952675D02*
Y-450000D01*
X-949825D01*
G01X-950875Y-452417D02*
X-952675D01*
G01X-945250Y-450000D02*
Y-455000D01*
G01X-946975Y-450000D02*
X-943525D01*
G01X-935500D02*
X-934450Y-455000D01*
X-933250Y-450000D01*
X-932050Y-455000D01*
X-931000Y-450000D01*
G01X-929125Y-455000D02*
X-927250Y-450000D01*
X-925375Y-455000D01*
G01X-926050Y-453250D02*
X-928450D01*
G01X-921250Y-455000D02*
Y-452750D01*
X-922750Y-450000D01*
G01X-919750D02*
X-921250Y-452750D01*
G54D28*
X-1302441Y-79700D03*
X-1307559D03*
Y-74200D03*
X-1302441D03*
Y-68700D03*
X-1307559D03*
Y-63200D03*
X-1302441D03*
X-1307559Y-57700D03*
X-1302441D03*
X-1307559Y-52200D03*
X-1302441D03*
X-1307559Y-41200D03*
X-1302441D03*
Y-46700D03*
X-1307559D03*
Y-30200D03*
X-1302441D03*
X-1307559Y-35700D03*
X-1302441D03*
X-1187559Y-40500D03*
X-1182441D03*
X-1187559Y-46500D03*
X-1182441D03*
X-1187359Y-29400D03*
X-1187487Y-23450D03*
X-1182369D03*
X-1187359Y-34900D03*
X-1182369Y-18250D03*
X-1187487D03*
X-1187409Y-12128D03*
X-1182291D03*
X-1187359Y-5800D03*
Y0D03*
X-1168559Y-38500D03*
Y-49500D03*
Y-44000D03*
Y-33000D03*
X-1182241Y-29400D03*
X-1168487Y-26950D03*
X-1182241Y-34900D03*
X-1168487Y-10750D03*
Y-21750D03*
Y-16250D03*
X-1182241Y-5800D03*
X-1168487Y-5450D03*
X-1182241Y0D03*
X-1163441Y-38500D03*
Y-49500D03*
Y-44000D03*
Y-33000D03*
X-1163369Y-26950D03*
Y-10750D03*
Y-21750D03*
Y-16250D03*
Y-5450D03*
X-1053787Y-52850D03*
X-1048669D03*
X-1045441Y-34000D03*
X-1050559D03*
X-1045441Y-10000D03*
X-1050559D03*
X-1045550Y-16600D03*
X-1050650D03*
X-438959Y-74100D03*
X-433841D03*
Y-79600D03*
X-438959D03*
X-433841Y-68600D03*
X-438959D03*
Y-63100D03*
X-433841D03*
X-438959Y-57600D03*
X-433841D03*
X-438959Y-46600D03*
X-433841D03*
X-438959Y-52100D03*
X-433841D03*
X-438959Y-41100D03*
X-433841D03*
X-438959Y-35600D03*
X-433841D03*
Y-29500D03*
X-438959D03*
X-318059Y-42000D03*
Y-47500D03*
X-317859Y-36400D03*
X-317987Y-24950D03*
X-317859Y-30900D03*
X-317987Y-19750D03*
X-317859Y-7300D03*
X-317909Y-13628D03*
X-317859Y-1500D03*
X-312941Y-42000D03*
Y-47500D03*
X-312741Y-36400D03*
X-312869Y-24950D03*
X-312741Y-30900D03*
X-312869Y-19750D03*
X-312741Y-7300D03*
X-312791Y-13628D03*
X-312741Y-1500D03*
X-299259Y-38000D03*
X-294141D03*
Y-48800D03*
X-299259D03*
X-294141Y-43300D03*
X-299259D03*
X-294141Y-32500D03*
X-299259D03*
X-298987Y-25950D03*
X-293869D03*
Y-20750D03*
X-298987D03*
X-299131Y-15250D03*
X-294013D03*
Y-9750D03*
X-299131D03*
X-298987Y-4450D03*
X-293869D03*
X-182209Y-52350D03*
X-177091D03*
X-178959Y-34470D03*
X-179059Y-10000D03*
X-178850Y-16500D03*
X-173841Y-34470D03*
X-173941Y-10000D03*
X-173750Y-16500D03*
G54D37*
X-1025000Y-50942D03*
Y1459D03*
X-1015157Y-105312D03*
X-997441D03*
X-981693Y-50942D03*
Y1459D03*
X-971850Y-105312D03*
X-954134D03*
X-938386Y-50942D03*
Y1459D03*
X-145079Y-105312D03*
X-154921Y-50942D03*
Y1459D03*
X-127362Y-105312D03*
X-111614Y-50942D03*
Y1459D03*
X-101772Y-105312D03*
X-84055D03*
X-68307Y-50942D03*
Y1459D03*
G54D19*
X-1488693Y-178940D03*
X-1476693Y-64840D03*
X-618614Y-178940D03*
X-606614Y-64840D03*
G54D47*
G01X-874510Y-499000D02*
Y-493000D01*
X-871290Y-499000D01*
Y-493000D01*
G01X-867200Y-499000D02*
X-867760Y-498900D01*
X-868250Y-498500D01*
X-868670Y-497900D01*
X-868950Y-497200D01*
X-869090Y-496400D01*
Y-495600D01*
X-868950Y-494800D01*
X-868670Y-494100D01*
X-868250Y-493500D01*
X-867760Y-493100D01*
X-867200Y-493000D01*
X-866640Y-493100D01*
X-866150Y-493500D01*
X-865730Y-494100D01*
X-865450Y-494800D01*
X-865310Y-495600D01*
Y-496400D01*
X-865450Y-497200D01*
X-865730Y-497900D01*
X-866150Y-498500D01*
X-866640Y-498900D01*
X-867200Y-499000D01*
G01X-861500Y-493000D02*
Y-499000D01*
G01X-863110Y-493000D02*
X-859890D01*
G01X-856640D02*
X-854960D01*
G01X-855800D02*
Y-499000D01*
G01X-856640D02*
X-854960D01*
G01X-848560Y-493500D02*
X-848980Y-493200D01*
X-849470Y-493000D01*
X-850030D01*
X-850660Y-493300D01*
X-851150Y-493800D01*
X-851500Y-494400D01*
X-851780Y-495400D01*
X-851850Y-496300D01*
X-851710Y-497200D01*
X-851500Y-497800D01*
X-851080Y-498400D01*
X-850590Y-498800D01*
X-850100Y-499000D01*
X-849610D01*
X-849120Y-498800D01*
X-848700Y-498500D01*
X-848350Y-498100D01*
G01X-843000Y-499000D02*
X-845800D01*
Y-493000D01*
X-843000D01*
G01X-844120Y-495900D02*
X-845800D01*
G01X-833000Y-499000D02*
X-833560Y-498900D01*
X-834050Y-498500D01*
X-834470Y-497900D01*
X-834750Y-497200D01*
X-834890Y-496400D01*
Y-495600D01*
X-834750Y-494800D01*
X-834470Y-494100D01*
X-834050Y-493500D01*
X-833560Y-493100D01*
X-833000Y-493000D01*
X-832440Y-493100D01*
X-831950Y-493500D01*
X-831530Y-494100D01*
X-831250Y-494800D01*
X-831110Y-495600D01*
Y-496400D01*
X-831250Y-497200D01*
X-831530Y-497900D01*
X-831950Y-498500D01*
X-832440Y-498900D01*
X-833000Y-499000D01*
G01X-828630D02*
Y-493000D01*
X-825970D01*
G01X-826950Y-495900D02*
X-828630D01*
G01X-817300Y-499000D02*
Y-493000D01*
X-815620D01*
X-815060Y-493300D01*
X-814640Y-494000D01*
X-814500Y-494800D01*
X-814640Y-495600D01*
X-814990Y-496200D01*
X-815620Y-496500D01*
X-817300D01*
G01X-811600Y-499000D02*
Y-493000D01*
X-809850D01*
X-809290Y-493300D01*
X-808940Y-493700D01*
X-808800Y-494500D01*
X-808940Y-495300D01*
X-809360Y-495800D01*
X-809850Y-496100D01*
X-811600D01*
G01X-809850D02*
X-808800Y-499000D01*
G01X-804500D02*
X-805060Y-498900D01*
X-805550Y-498500D01*
X-805970Y-497900D01*
X-806250Y-497200D01*
X-806390Y-496400D01*
Y-495600D01*
X-806250Y-494800D01*
X-805970Y-494100D01*
X-805550Y-493500D01*
X-805060Y-493100D01*
X-804500Y-493000D01*
X-803940Y-493100D01*
X-803450Y-493500D01*
X-803030Y-494100D01*
X-802750Y-494800D01*
X-802610Y-495600D01*
Y-496400D01*
X-802750Y-497200D01*
X-803030Y-497900D01*
X-803450Y-498500D01*
X-803940Y-498900D01*
X-804500Y-499000D01*
G01X-800200D02*
Y-493000D01*
X-798520D01*
X-797960Y-493300D01*
X-797540Y-494000D01*
X-797400Y-494800D01*
X-797540Y-495600D01*
X-797890Y-496200D01*
X-798520Y-496500D01*
X-800200D01*
G01X-794500Y-499000D02*
Y-493000D01*
X-792750D01*
X-792190Y-493300D01*
X-791840Y-493700D01*
X-791700Y-494500D01*
X-791840Y-495300D01*
X-792260Y-495800D01*
X-792750Y-496100D01*
X-794500D01*
G01X-792750D02*
X-791700Y-499000D01*
G01X-788240Y-493000D02*
X-786560D01*
G01X-787400D02*
Y-499000D01*
G01X-788240D02*
X-786560D01*
G01X-780300D02*
X-783100D01*
Y-493000D01*
X-780300D01*
G01X-781420Y-495900D02*
X-783100D01*
G01X-776000Y-493000D02*
Y-499000D01*
G01X-777610Y-493000D02*
X-774390D01*
G01X-772050Y-499000D02*
X-770300Y-493000D01*
X-768550Y-499000D01*
G01X-769180Y-496900D02*
X-771420D01*
G01X-766000Y-499000D02*
Y-493000D01*
X-764250D01*
X-763690Y-493300D01*
X-763340Y-493700D01*
X-763200Y-494500D01*
X-763340Y-495300D01*
X-763760Y-495800D01*
X-764250Y-496100D01*
X-766000D01*
G01X-764250D02*
X-763200Y-499000D01*
G01X-758900D02*
Y-496300D01*
X-760300Y-493000D01*
G01X-757500D02*
X-758900Y-496300D01*
G01X-748900Y-499000D02*
Y-493000D01*
X-747220D01*
X-746660Y-493300D01*
X-746240Y-494000D01*
X-746100Y-494800D01*
X-746240Y-495600D01*
X-746590Y-496200D01*
X-747220Y-496500D01*
X-748900D01*
G01X-743200Y-499000D02*
Y-493000D01*
X-741450D01*
X-740890Y-493300D01*
X-740540Y-493700D01*
X-740400Y-494500D01*
X-740540Y-495300D01*
X-740960Y-495800D01*
X-741450Y-496100D01*
X-743200D01*
G01X-741450D02*
X-740400Y-499000D01*
G01X-736100D02*
X-736660Y-498900D01*
X-737150Y-498500D01*
X-737570Y-497900D01*
X-737850Y-497200D01*
X-737990Y-496400D01*
Y-495600D01*
X-737850Y-494800D01*
X-737570Y-494100D01*
X-737150Y-493500D01*
X-736660Y-493100D01*
X-736100Y-493000D01*
X-735540Y-493100D01*
X-735050Y-493500D01*
X-734630Y-494100D01*
X-734350Y-494800D01*
X-734210Y-495600D01*
Y-496400D01*
X-734350Y-497200D01*
X-734630Y-497900D01*
X-735050Y-498500D01*
X-735540Y-498900D01*
X-736100Y-499000D01*
G01X-731800D02*
Y-493000D01*
X-730120D01*
X-729560Y-493300D01*
X-729140Y-494000D01*
X-729000Y-494800D01*
X-729140Y-495600D01*
X-729490Y-496200D01*
X-730120Y-496500D01*
X-731800D01*
G01X-723300Y-499000D02*
X-726100D01*
Y-493000D01*
X-723300D01*
G01X-724420Y-495900D02*
X-726100D01*
G01X-720400Y-499000D02*
Y-493000D01*
X-718650D01*
X-718090Y-493300D01*
X-717740Y-493700D01*
X-717600Y-494500D01*
X-717740Y-495300D01*
X-718160Y-495800D01*
X-718650Y-496100D01*
X-720400D01*
G01X-718650D02*
X-717600Y-499000D01*
G01X-713300Y-493000D02*
Y-499000D01*
G01X-714910Y-493000D02*
X-711690D01*
G01X-707600Y-499000D02*
Y-496300D01*
X-709000Y-493000D01*
G01X-706200D02*
X-707600Y-496300D01*
G01X-701900Y-499200D02*
X-702040Y-499100D01*
Y-498900D01*
X-701900Y-498800D01*
X-701760Y-498900D01*
Y-499100D01*
X-701900Y-499200D01*
G01Y-496500D02*
X-702040Y-496400D01*
Y-496200D01*
X-701900Y-496100D01*
X-701760Y-496200D01*
Y-496400D01*
X-701900Y-496500D01*
G54D38*
X-1015157Y-95824D03*
X-1012205Y-93068D03*
X-1009252Y-98580D03*
X-1015157Y-80864D03*
X-1012205Y-78108D03*
X-1009252Y-83620D03*
X-1015157Y-65903D03*
X-1012205Y-63147D03*
X-1009252Y-68659D03*
X-1015157Y-50942D03*
X-1012205Y-48187D03*
X-1009252Y-53698D03*
X-1006299Y-95824D03*
X-1000394Y-98580D03*
X-1003346Y-93068D03*
X-997441Y-95824D03*
X-994488Y-93068D03*
X-1000394Y-83620D03*
X-1006299Y-80864D03*
X-1003346Y-78108D03*
X-997441Y-80864D03*
X-994488Y-78108D03*
X-1006299Y-65903D03*
X-1003346Y-63147D03*
X-1000394Y-68659D03*
X-997441Y-65903D03*
X-994488Y-63147D03*
X-1006299Y-50942D03*
X-1003346Y-48187D03*
X-1000394Y-53698D03*
X-997441Y-50942D03*
X-994488Y-48187D03*
X-991535Y-98580D03*
Y-83620D03*
Y-68659D03*
Y-53698D03*
X-971850Y-95824D03*
X-968898Y-93068D03*
X-965945Y-98580D03*
X-962992Y-95824D03*
X-971850Y-80864D03*
X-965945Y-83620D03*
X-962992Y-80864D03*
X-968898Y-78108D03*
X-971850Y-65903D03*
X-965945Y-68659D03*
X-962992Y-65903D03*
X-968898Y-63147D03*
X-971850Y-50942D03*
X-965945Y-53698D03*
X-962992Y-50942D03*
X-968898Y-48187D03*
X-960039Y-93068D03*
X-957087Y-98580D03*
X-954134Y-95824D03*
X-951181Y-93068D03*
X-948228Y-98580D03*
X-960039Y-78108D03*
X-948228Y-83620D03*
X-957087D03*
X-954134Y-80864D03*
X-951181Y-78108D03*
X-960039Y-63147D03*
X-948228Y-68659D03*
X-957087D03*
X-954134Y-65903D03*
X-951181Y-63147D03*
X-960039Y-48187D03*
X-948228Y-53698D03*
X-957087D03*
X-954134Y-50942D03*
X-951181Y-48187D03*
X-145079Y-95824D03*
Y-80864D03*
Y-65903D03*
Y-50942D03*
X-142126Y-93068D03*
X-139173Y-98580D03*
X-136220Y-95824D03*
X-130315Y-98580D03*
X-133268Y-93068D03*
X-127362Y-95824D03*
X-142126Y-78108D03*
X-139173Y-83620D03*
X-130315D03*
X-136220Y-80864D03*
X-133268Y-78108D03*
X-127362Y-80864D03*
X-142126Y-63147D03*
X-139173Y-68659D03*
X-136220Y-65903D03*
X-133268Y-63147D03*
X-130315Y-68659D03*
X-127362Y-65903D03*
X-142126Y-48187D03*
X-139173Y-53698D03*
X-136220Y-50942D03*
X-133268Y-48187D03*
X-130315Y-53698D03*
X-127362Y-50942D03*
X-121457Y-98580D03*
X-124409Y-93068D03*
X-121457Y-83620D03*
X-124409Y-78108D03*
X-121457Y-68659D03*
X-124409Y-63147D03*
X-121457Y-53698D03*
X-124409Y-48187D03*
X-101772Y-95824D03*
X-98819Y-93068D03*
X-95866Y-98580D03*
X-101772Y-80864D03*
X-95866Y-83620D03*
X-98819Y-78108D03*
X-101772Y-65903D03*
X-95866Y-68659D03*
X-98819Y-63147D03*
X-101772Y-50942D03*
X-95866Y-53698D03*
X-98819Y-48187D03*
X-92913Y-95824D03*
X-89961Y-93068D03*
X-87008Y-98580D03*
X-84055Y-95824D03*
X-81102Y-93068D03*
X-92913Y-80864D03*
X-89961Y-78108D03*
X-87008Y-83620D03*
X-84055Y-80864D03*
X-81102Y-78108D03*
X-92913Y-65903D03*
X-89961Y-63147D03*
X-87008Y-68659D03*
X-84055Y-65903D03*
X-81102Y-63147D03*
X-92913Y-50942D03*
X-89961Y-48187D03*
X-87008Y-53698D03*
X-84055Y-50942D03*
X-81102Y-48187D03*
X-78150Y-98580D03*
Y-83620D03*
Y-68659D03*
Y-53698D03*
G54D29*
X-1282480Y-172283D03*
Y-130157D03*
Y-94724D03*
Y-59291D03*
Y-23858D03*
X-1253740Y-184094D03*
X-1225394D03*
X-1207677Y-154567D03*
Y-112441D03*
Y-77008D03*
Y-41575D03*
Y-6142D03*
X-412402Y-172283D03*
Y-130157D03*
Y-94724D03*
Y-59291D03*
Y-23858D03*
X-383661Y-184094D03*
X-355315D03*
X-337598Y-154567D03*
Y-112441D03*
Y-77008D03*
Y-41575D03*
Y-6142D03*
G54D48*
G01X-1189333Y-572500D02*
Y-565500D01*
X-1187667D01*
X-1187000Y-565850D01*
X-1186500Y-566317D01*
X-1186083Y-567017D01*
X-1185750Y-567833D01*
X-1185667Y-569000D01*
X-1185750Y-570167D01*
X-1186083Y-570983D01*
X-1186500Y-571684D01*
X-1187000Y-572150D01*
X-1187667Y-572500D01*
X-1189333D01*
G01X-1180700D02*
X-1181367Y-572383D01*
X-1181950Y-571917D01*
X-1182450Y-571217D01*
X-1182783Y-570400D01*
X-1182950Y-569467D01*
Y-568533D01*
X-1182783Y-567600D01*
X-1182450Y-566783D01*
X-1181950Y-566083D01*
X-1181367Y-565617D01*
X-1180700Y-565500D01*
X-1180033Y-565617D01*
X-1179450Y-566083D01*
X-1178950Y-566783D01*
X-1178617Y-567600D01*
X-1178450Y-568533D01*
Y-569467D01*
X-1178617Y-570400D01*
X-1178950Y-571217D01*
X-1179450Y-571917D01*
X-1180033Y-572383D01*
X-1180700Y-572500D01*
G01X-1172067Y-566083D02*
X-1172567Y-565733D01*
X-1173150Y-565500D01*
X-1173817D01*
X-1174567Y-565850D01*
X-1175150Y-566433D01*
X-1175567Y-567133D01*
X-1175900Y-568300D01*
X-1175983Y-569350D01*
X-1175817Y-570400D01*
X-1175567Y-571100D01*
X-1175067Y-571800D01*
X-1174483Y-572267D01*
X-1173900Y-572500D01*
X-1173317D01*
X-1172733Y-572267D01*
X-1172233Y-571917D01*
X-1171817Y-571450D01*
G01X-1168933Y-565500D02*
Y-570517D01*
X-1168600Y-571567D01*
X-1167933Y-572267D01*
X-1167100Y-572500D01*
X-1166267Y-572267D01*
X-1165600Y-571567D01*
X-1165267Y-570517D01*
Y-565500D01*
G01X-1162467Y-572500D02*
Y-565500D01*
X-1160300Y-571333D01*
X-1158133Y-565500D01*
Y-572500D01*
G01X-1151833D02*
X-1155167D01*
Y-565500D01*
X-1151833D01*
G01X-1153167Y-568883D02*
X-1155167D01*
G01X-1148617Y-572500D02*
Y-565500D01*
X-1144783Y-572500D01*
Y-565500D01*
G01X-1139900D02*
Y-572500D01*
G01X-1141817Y-565500D02*
X-1137983D01*
G01X-1128217Y-572500D02*
Y-565500D01*
X-1124383Y-572500D01*
Y-565500D01*
G01X-1121333D02*
Y-570517D01*
X-1121000Y-571567D01*
X-1120333Y-572267D01*
X-1119500Y-572500D01*
X-1118667Y-572267D01*
X-1118000Y-571567D01*
X-1117667Y-570517D01*
Y-565500D01*
G01X-1114867Y-572500D02*
Y-565500D01*
X-1112700Y-571333D01*
X-1110533Y-565500D01*
Y-572500D01*
G01X-1105233Y-568767D02*
X-1104900Y-568417D01*
X-1104650Y-567833D01*
X-1104483Y-567017D01*
X-1104650Y-566317D01*
X-1104983Y-565850D01*
X-1105567Y-565500D01*
X-1107817D01*
Y-572500D01*
X-1105067D01*
X-1104483Y-572033D01*
X-1104150Y-571333D01*
X-1103983Y-570517D01*
X-1104150Y-569700D01*
X-1104650Y-569000D01*
X-1105233Y-568767D01*
X-1107817D01*
G01X-1097433Y-572500D02*
X-1100767D01*
Y-565500D01*
X-1097433D01*
G01X-1098767Y-568883D02*
X-1100767D01*
G01X-1093967Y-572500D02*
Y-565500D01*
X-1091883D01*
X-1091217Y-565850D01*
X-1090800Y-566317D01*
X-1090633Y-567250D01*
X-1090800Y-568183D01*
X-1091300Y-568767D01*
X-1091883Y-569117D01*
X-1093967D01*
G01X-1091883D02*
X-1090633Y-572500D01*
G01X-1189250Y-531567D02*
X-1188583Y-532150D01*
X-1187833Y-532500D01*
X-1187167D01*
X-1186500Y-532150D01*
X-1186000Y-531567D01*
X-1185750Y-530750D01*
X-1185917Y-529933D01*
X-1186333Y-529233D01*
X-1187083Y-528767D01*
X-1188083Y-528533D01*
X-1188667Y-528067D01*
X-1188917Y-527250D01*
X-1188750Y-526433D01*
X-1188333Y-525850D01*
X-1187750Y-525500D01*
X-1187167D01*
X-1186583Y-525733D01*
X-1186083Y-526317D01*
G01X-1182450Y-532500D02*
Y-525500D01*
G01X-1178950D02*
Y-532500D01*
G01Y-529000D02*
X-1182450D01*
G01X-1172233Y-532500D02*
X-1175567D01*
Y-525500D01*
X-1172233D01*
G01X-1173567Y-528883D02*
X-1175567D01*
G01X-1165433Y-532500D02*
X-1168767D01*
Y-525500D01*
X-1165433D01*
G01X-1166767Y-528883D02*
X-1168767D01*
G01X-1160300Y-525500D02*
Y-532500D01*
G01X-1162217Y-525500D02*
X-1158383D01*
G01X-1146700D02*
Y-532500D01*
G01X-1148617Y-525500D02*
X-1144783D01*
G01X-1140900D02*
X-1138900D01*
G01X-1139900D02*
Y-532500D01*
G01X-1140900D02*
X-1138900D01*
G01X-1133100Y-525500D02*
Y-532500D01*
G01X-1135017Y-525500D02*
X-1131183D01*
G01X-1127967D02*
Y-532500D01*
X-1124633D01*
G01X-1117833D02*
X-1121167D01*
Y-525500D01*
X-1117833D01*
G01X-1119167Y-528883D02*
X-1121167D01*
G01X-1112700Y-532733D02*
X-1112867Y-532617D01*
Y-532383D01*
X-1112700Y-532267D01*
X-1112533Y-532383D01*
Y-532617D01*
X-1112700Y-532733D01*
G01Y-529584D02*
X-1112867Y-529467D01*
Y-529233D01*
X-1112700Y-529117D01*
X-1112533Y-529233D01*
Y-529467D01*
X-1112700Y-529584D01*
G01X-1187500Y-485500D02*
Y-492500D01*
G01X-1189417Y-485500D02*
X-1185583D01*
G01X-1181700D02*
X-1179700D01*
G01X-1180700D02*
Y-492500D01*
G01X-1181700D02*
X-1179700D01*
G01X-1173900Y-485500D02*
Y-492500D01*
G01X-1175817Y-485500D02*
X-1171983D01*
G01X-1168767D02*
Y-492500D01*
X-1165433D01*
G01X-1158633D02*
X-1161967D01*
Y-485500D01*
X-1158633D01*
G01X-1159967Y-488883D02*
X-1161967D01*
G01X-916667Y-570000D02*
Y-563000D01*
X-914583D01*
X-913917Y-563350D01*
X-913500Y-563817D01*
X-913333Y-564750D01*
X-913500Y-565683D01*
X-914000Y-566267D01*
X-914583Y-566617D01*
X-916667D01*
G01X-914583D02*
X-913333Y-570000D01*
G01X-906533D02*
X-909867D01*
Y-563000D01*
X-906533D01*
G01X-907867Y-566383D02*
X-909867D01*
G01X-903483Y-563000D02*
X-901400Y-570000D01*
X-899317Y-563000D01*
G01X-907850Y-451567D02*
X-907183Y-452150D01*
X-906433Y-452500D01*
X-905767D01*
X-905100Y-452150D01*
X-904600Y-451567D01*
X-904350Y-450750D01*
X-904517Y-449933D01*
X-904933Y-449233D01*
X-905683Y-448767D01*
X-906683Y-448533D01*
X-907267Y-448067D01*
X-907517Y-447250D01*
X-907350Y-446433D01*
X-906933Y-445850D01*
X-906350Y-445500D01*
X-905767D01*
X-905183Y-445733D01*
X-904683Y-446317D01*
G01X-897467Y-446083D02*
X-897967Y-445733D01*
X-898550Y-445500D01*
X-899217D01*
X-899967Y-445850D01*
X-900550Y-446433D01*
X-900967Y-447133D01*
X-901300Y-448300D01*
X-901383Y-449350D01*
X-901217Y-450400D01*
X-900967Y-451100D01*
X-900467Y-451800D01*
X-899883Y-452267D01*
X-899300Y-452500D01*
X-898717D01*
X-898133Y-452267D01*
X-897633Y-451917D01*
X-897217Y-451450D01*
G01X-894583Y-452500D02*
X-892500Y-445500D01*
X-890417Y-452500D01*
G01X-891167Y-450050D02*
X-893833D01*
G01X-887367Y-445500D02*
Y-452500D01*
X-884033D01*
G01X-877233D02*
X-880567D01*
Y-445500D01*
X-877233D01*
G01X-878567Y-448883D02*
X-880567D01*
G01X-874333Y-572500D02*
Y-565500D01*
X-872667D01*
X-872000Y-565850D01*
X-871500Y-566317D01*
X-871083Y-567017D01*
X-870750Y-567833D01*
X-870667Y-569000D01*
X-870750Y-570167D01*
X-871083Y-570983D01*
X-871500Y-571684D01*
X-872000Y-572150D01*
X-872667Y-572500D01*
X-874333D01*
G01X-866700Y-565500D02*
X-864700D01*
G01X-865700D02*
Y-572500D01*
G01X-866700D02*
X-864700D01*
G01X-860650Y-571567D02*
X-859983Y-572150D01*
X-859233Y-572500D01*
X-858567D01*
X-857900Y-572150D01*
X-857400Y-571567D01*
X-857150Y-570750D01*
X-857317Y-569933D01*
X-857733Y-569233D01*
X-858483Y-568767D01*
X-859483Y-568533D01*
X-860067Y-568067D01*
X-860317Y-567250D01*
X-860150Y-566433D01*
X-859733Y-565850D01*
X-859150Y-565500D01*
X-858567D01*
X-857983Y-565733D01*
X-857483Y-566317D01*
G01X-850267Y-566083D02*
X-850767Y-565733D01*
X-851350Y-565500D01*
X-852017D01*
X-852767Y-565850D01*
X-853350Y-566433D01*
X-853767Y-567133D01*
X-854100Y-568300D01*
X-854183Y-569350D01*
X-854017Y-570400D01*
X-853767Y-571100D01*
X-853267Y-571800D01*
X-852683Y-572267D01*
X-852100Y-572500D01*
X-851517D01*
X-850933Y-572267D01*
X-850433Y-571917D01*
X-850017Y-571450D01*
G01X-846967Y-565500D02*
Y-572500D01*
X-843633D01*
G01X-838500D02*
X-839167Y-572383D01*
X-839750Y-571917D01*
X-840250Y-571217D01*
X-840583Y-570400D01*
X-840750Y-569467D01*
Y-568533D01*
X-840583Y-567600D01*
X-840250Y-566783D01*
X-839750Y-566083D01*
X-839167Y-565617D01*
X-838500Y-565500D01*
X-837833Y-565617D01*
X-837250Y-566083D01*
X-836750Y-566783D01*
X-836417Y-567600D01*
X-836250Y-568533D01*
Y-569467D01*
X-836417Y-570400D01*
X-836750Y-571217D01*
X-837250Y-571917D01*
X-837833Y-572383D01*
X-838500Y-572500D01*
G01X-833450Y-571567D02*
X-832783Y-572150D01*
X-832033Y-572500D01*
X-831367D01*
X-830700Y-572150D01*
X-830200Y-571567D01*
X-829950Y-570750D01*
X-830117Y-569933D01*
X-830533Y-569233D01*
X-831283Y-568767D01*
X-832283Y-568533D01*
X-832867Y-568067D01*
X-833117Y-567250D01*
X-832950Y-566433D01*
X-832533Y-565850D01*
X-831950Y-565500D01*
X-831367D01*
X-830783Y-565733D01*
X-830283Y-566317D01*
G01X-823233Y-572500D02*
X-826567D01*
Y-565500D01*
X-823233D01*
G01X-824567Y-568883D02*
X-826567D01*
G01X-819933Y-572500D02*
Y-565500D01*
X-818267D01*
X-817600Y-565850D01*
X-817100Y-566317D01*
X-816683Y-567017D01*
X-816350Y-567833D01*
X-816267Y-569000D01*
X-816350Y-570167D01*
X-816683Y-570983D01*
X-817100Y-571684D01*
X-817600Y-572150D01*
X-818267Y-572500D01*
X-819933D01*
G01X-807000Y-565500D02*
X-805833Y-572500D01*
X-804500Y-565500D01*
X-803167Y-572500D01*
X-802000Y-565500D01*
G01X-798700D02*
X-796700D01*
G01X-797700D02*
Y-572500D01*
G01X-798700D02*
X-796700D01*
G01X-790900Y-565500D02*
Y-572500D01*
G01X-792817Y-565500D02*
X-788983D01*
G01X-785850Y-572500D02*
Y-565500D01*
G01X-782350D02*
Y-572500D01*
G01Y-569000D02*
X-785850D01*
G01X-777300Y-572500D02*
X-777967Y-572383D01*
X-778550Y-571917D01*
X-779050Y-571217D01*
X-779383Y-570400D01*
X-779550Y-569467D01*
Y-568533D01*
X-779383Y-567600D01*
X-779050Y-566783D01*
X-778550Y-566083D01*
X-777967Y-565617D01*
X-777300Y-565500D01*
X-776633Y-565617D01*
X-776050Y-566083D01*
X-775550Y-566783D01*
X-775217Y-567600D01*
X-775050Y-568533D01*
Y-569467D01*
X-775217Y-570400D01*
X-775550Y-571217D01*
X-776050Y-571917D01*
X-776633Y-572383D01*
X-777300Y-572500D01*
G01X-772333Y-565500D02*
Y-570517D01*
X-772000Y-571567D01*
X-771333Y-572267D01*
X-770500Y-572500D01*
X-769667Y-572267D01*
X-769000Y-571567D01*
X-768667Y-570517D01*
Y-565500D01*
G01X-763700D02*
Y-572500D01*
G01X-765617Y-565500D02*
X-761783D01*
G01X-750100D02*
Y-572500D01*
G01X-752017Y-565500D02*
X-748183D01*
G01X-745050Y-572500D02*
Y-565500D01*
G01X-741550D02*
Y-572500D01*
G01Y-569000D02*
X-745050D01*
G01X-734833Y-572500D02*
X-738167D01*
Y-565500D01*
X-734833D01*
G01X-736167Y-568883D02*
X-738167D01*
G01X-724567Y-572500D02*
Y-565500D01*
X-722567D01*
X-721900Y-565850D01*
X-721400Y-566667D01*
X-721233Y-567600D01*
X-721400Y-568533D01*
X-721817Y-569233D01*
X-722567Y-569584D01*
X-724567D01*
G01X-717767Y-572500D02*
Y-565500D01*
X-715683D01*
X-715017Y-565850D01*
X-714600Y-566317D01*
X-714433Y-567250D01*
X-714600Y-568183D01*
X-715100Y-568767D01*
X-715683Y-569117D01*
X-717767D01*
G01X-715683D02*
X-714433Y-572500D01*
G01X-710300Y-565500D02*
X-708300D01*
G01X-709300D02*
Y-572500D01*
G01X-710300D02*
X-708300D01*
G01X-702500D02*
X-703167Y-572383D01*
X-703750Y-571917D01*
X-704250Y-571217D01*
X-704583Y-570400D01*
X-704750Y-569467D01*
Y-568533D01*
X-704583Y-567600D01*
X-704250Y-566783D01*
X-703750Y-566083D01*
X-703167Y-565617D01*
X-702500Y-565500D01*
X-701833Y-565617D01*
X-701250Y-566083D01*
X-700750Y-566783D01*
X-700417Y-567600D01*
X-700250Y-568533D01*
Y-569467D01*
X-700417Y-570400D01*
X-700750Y-571217D01*
X-701250Y-571917D01*
X-701833Y-572383D01*
X-702500Y-572500D01*
G01X-697367D02*
Y-565500D01*
X-695283D01*
X-694617Y-565850D01*
X-694200Y-566317D01*
X-694033Y-567250D01*
X-694200Y-568183D01*
X-694700Y-568767D01*
X-695283Y-569117D01*
X-697367D01*
G01X-695283D02*
X-694033Y-572500D01*
G01X-684600Y-565500D02*
X-683433Y-572500D01*
X-682100Y-565500D01*
X-680767Y-572500D01*
X-679600Y-565500D01*
G01X-676967Y-572500D02*
Y-565500D01*
X-674883D01*
X-674217Y-565850D01*
X-673800Y-566317D01*
X-673633Y-567250D01*
X-673800Y-568183D01*
X-674300Y-568767D01*
X-674883Y-569117D01*
X-676967D01*
G01X-674883D02*
X-673633Y-572500D01*
G01X-669500Y-565500D02*
X-667500D01*
G01X-668500D02*
Y-572500D01*
G01X-669500D02*
X-667500D01*
G01X-661700Y-565500D02*
Y-572500D01*
G01X-663617Y-565500D02*
X-659783D01*
G01X-654900D02*
Y-572500D01*
G01X-656817Y-565500D02*
X-652983D01*
G01X-646433Y-572500D02*
X-649767D01*
Y-565500D01*
X-646433D01*
G01X-647767Y-568883D02*
X-649767D01*
G01X-643217Y-572500D02*
Y-565500D01*
X-639383Y-572500D01*
Y-565500D01*
G01X-625867Y-566083D02*
X-626367Y-565733D01*
X-626950Y-565500D01*
X-627617D01*
X-628367Y-565850D01*
X-628950Y-566433D01*
X-629367Y-567133D01*
X-629700Y-568300D01*
X-629783Y-569350D01*
X-629617Y-570400D01*
X-629367Y-571100D01*
X-628867Y-571800D01*
X-628283Y-572267D01*
X-627700Y-572500D01*
X-627117D01*
X-626533Y-572267D01*
X-626033Y-571917D01*
X-625617Y-571450D01*
G01X-620900Y-572500D02*
X-621567Y-572383D01*
X-622150Y-571917D01*
X-622650Y-571217D01*
X-622983Y-570400D01*
X-623150Y-569467D01*
Y-568533D01*
X-622983Y-567600D01*
X-622650Y-566783D01*
X-622150Y-566083D01*
X-621567Y-565617D01*
X-620900Y-565500D01*
X-620233Y-565617D01*
X-619650Y-566083D01*
X-619150Y-566783D01*
X-618817Y-567600D01*
X-618650Y-568533D01*
Y-569467D01*
X-618817Y-570400D01*
X-619150Y-571217D01*
X-619650Y-571917D01*
X-620233Y-572383D01*
X-620900Y-572500D01*
G01X-616017D02*
Y-565500D01*
X-612183Y-572500D01*
Y-565500D01*
G01X-609050Y-571567D02*
X-608383Y-572150D01*
X-607633Y-572500D01*
X-606967D01*
X-606300Y-572150D01*
X-605800Y-571567D01*
X-605550Y-570750D01*
X-605717Y-569933D01*
X-606133Y-569233D01*
X-606883Y-568767D01*
X-607883Y-568533D01*
X-608467Y-568067D01*
X-608717Y-567250D01*
X-608550Y-566433D01*
X-608133Y-565850D01*
X-607550Y-565500D01*
X-606967D01*
X-606383Y-565733D01*
X-605883Y-566317D01*
G01X-598833Y-572500D02*
X-602167D01*
Y-565500D01*
X-598833D01*
G01X-600167Y-568883D02*
X-602167D01*
G01X-595617Y-572500D02*
Y-565500D01*
X-591783Y-572500D01*
Y-565500D01*
G01X-586900D02*
Y-572500D01*
G01X-588817Y-565500D02*
X-584983D01*
G01X-872500Y-587500D02*
X-873167Y-587383D01*
X-873750Y-586917D01*
X-874250Y-586217D01*
X-874583Y-585400D01*
X-874750Y-584467D01*
Y-583533D01*
X-874583Y-582600D01*
X-874250Y-581783D01*
X-873750Y-581083D01*
X-873167Y-580617D01*
X-872500Y-580500D01*
X-871833Y-580617D01*
X-871250Y-581083D01*
X-870750Y-581783D01*
X-870417Y-582600D01*
X-870250Y-583533D01*
Y-584467D01*
X-870417Y-585400D01*
X-870750Y-586217D01*
X-871250Y-586917D01*
X-871833Y-587383D01*
X-872500Y-587500D01*
G01X-867283D02*
Y-580500D01*
X-864117D01*
G01X-865283Y-583883D02*
X-867283D01*
G01X-854267Y-587500D02*
Y-580500D01*
X-852100Y-586333D01*
X-849933Y-580500D01*
Y-587500D01*
G01X-846300Y-580500D02*
X-844300D01*
G01X-845300D02*
Y-587500D01*
G01X-846300D02*
X-844300D01*
G01X-836667Y-581083D02*
X-837167Y-580733D01*
X-837750Y-580500D01*
X-838417D01*
X-839167Y-580850D01*
X-839750Y-581433D01*
X-840167Y-582133D01*
X-840500Y-583300D01*
X-840583Y-584350D01*
X-840417Y-585400D01*
X-840167Y-586100D01*
X-839667Y-586800D01*
X-839083Y-587267D01*
X-838500Y-587500D01*
X-837917D01*
X-837333Y-587267D01*
X-836833Y-586917D01*
X-836417Y-586450D01*
G01X-833367Y-587500D02*
Y-580500D01*
X-831283D01*
X-830617Y-580850D01*
X-830200Y-581317D01*
X-830033Y-582250D01*
X-830200Y-583183D01*
X-830700Y-583767D01*
X-831283Y-584117D01*
X-833367D01*
G01X-831283D02*
X-830033Y-587500D01*
G01X-824900D02*
X-825567Y-587383D01*
X-826150Y-586917D01*
X-826650Y-586217D01*
X-826983Y-585400D01*
X-827150Y-584467D01*
Y-583533D01*
X-826983Y-582600D01*
X-826650Y-581783D01*
X-826150Y-581083D01*
X-825567Y-580617D01*
X-824900Y-580500D01*
X-824233Y-580617D01*
X-823650Y-581083D01*
X-823150Y-581783D01*
X-822817Y-582600D01*
X-822650Y-583533D01*
Y-584467D01*
X-822817Y-585400D01*
X-823150Y-586217D01*
X-823650Y-586917D01*
X-824233Y-587383D01*
X-824900Y-587500D01*
G01X-819850Y-586567D02*
X-819183Y-587150D01*
X-818433Y-587500D01*
X-817767D01*
X-817100Y-587150D01*
X-816600Y-586567D01*
X-816350Y-585750D01*
X-816517Y-584933D01*
X-816933Y-584233D01*
X-817683Y-583767D01*
X-818683Y-583533D01*
X-819267Y-583067D01*
X-819517Y-582250D01*
X-819350Y-581433D01*
X-818933Y-580850D01*
X-818350Y-580500D01*
X-817767D01*
X-817183Y-580733D01*
X-816683Y-581317D01*
G01X-811300Y-587500D02*
X-811967Y-587383D01*
X-812550Y-586917D01*
X-813050Y-586217D01*
X-813383Y-585400D01*
X-813550Y-584467D01*
Y-583533D01*
X-813383Y-582600D01*
X-813050Y-581783D01*
X-812550Y-581083D01*
X-811967Y-580617D01*
X-811300Y-580500D01*
X-810633Y-580617D01*
X-810050Y-581083D01*
X-809550Y-581783D01*
X-809217Y-582600D01*
X-809050Y-583533D01*
Y-584467D01*
X-809217Y-585400D01*
X-809550Y-586217D01*
X-810050Y-586917D01*
X-810633Y-587383D01*
X-811300Y-587500D01*
G01X-806083D02*
Y-580500D01*
X-802917D01*
G01X-804083Y-583883D02*
X-806083D01*
G01X-797700Y-580500D02*
Y-587500D01*
G01X-799617Y-580500D02*
X-795783D01*
G01X-782267Y-581083D02*
X-782767Y-580733D01*
X-783350Y-580500D01*
X-784017D01*
X-784767Y-580850D01*
X-785350Y-581433D01*
X-785767Y-582133D01*
X-786100Y-583300D01*
X-786183Y-584350D01*
X-786017Y-585400D01*
X-785767Y-586100D01*
X-785267Y-586800D01*
X-784683Y-587267D01*
X-784100Y-587500D01*
X-783517D01*
X-782933Y-587267D01*
X-782433Y-586917D01*
X-782017Y-586450D01*
G01X-777300Y-587500D02*
X-777967Y-587383D01*
X-778550Y-586917D01*
X-779050Y-586217D01*
X-779383Y-585400D01*
X-779550Y-584467D01*
Y-583533D01*
X-779383Y-582600D01*
X-779050Y-581783D01*
X-778550Y-581083D01*
X-777967Y-580617D01*
X-777300Y-580500D01*
X-776633Y-580617D01*
X-776050Y-581083D01*
X-775550Y-581783D01*
X-775217Y-582600D01*
X-775050Y-583533D01*
Y-584467D01*
X-775217Y-585400D01*
X-775550Y-586217D01*
X-776050Y-586917D01*
X-776633Y-587383D01*
X-777300Y-587500D01*
G01X-772167D02*
Y-580500D01*
X-770083D01*
X-769417Y-580850D01*
X-769000Y-581317D01*
X-768833Y-582250D01*
X-769000Y-583183D01*
X-769500Y-583767D01*
X-770083Y-584117D01*
X-772167D01*
G01X-770083D02*
X-768833Y-587500D01*
G01X-765367D02*
Y-580500D01*
X-763367D01*
X-762700Y-580850D01*
X-762200Y-581667D01*
X-762033Y-582600D01*
X-762200Y-583533D01*
X-762617Y-584233D01*
X-763367Y-584584D01*
X-765367D01*
G01X-756900Y-587500D02*
X-757567Y-587383D01*
X-758150Y-586917D01*
X-758650Y-586217D01*
X-758983Y-585400D01*
X-759150Y-584467D01*
Y-583533D01*
X-758983Y-582600D01*
X-758650Y-581783D01*
X-758150Y-581083D01*
X-757567Y-580617D01*
X-756900Y-580500D01*
X-756233Y-580617D01*
X-755650Y-581083D01*
X-755150Y-581783D01*
X-754817Y-582600D01*
X-754650Y-583533D01*
Y-584467D01*
X-754817Y-585400D01*
X-755150Y-586217D01*
X-755650Y-586917D01*
X-756233Y-587383D01*
X-756900Y-587500D01*
G01X-751767D02*
Y-580500D01*
X-749683D01*
X-749017Y-580850D01*
X-748600Y-581317D01*
X-748433Y-582250D01*
X-748600Y-583183D01*
X-749100Y-583767D01*
X-749683Y-584117D01*
X-751767D01*
G01X-749683D02*
X-748433Y-587500D01*
G01X-745383D02*
X-743300Y-580500D01*
X-741217Y-587500D01*
G01X-741967Y-585050D02*
X-744633D01*
G01X-736500Y-580500D02*
Y-587500D01*
G01X-738417Y-580500D02*
X-734583D01*
G01X-730700D02*
X-728700D01*
G01X-729700D02*
Y-587500D01*
G01X-730700D02*
X-728700D01*
G01X-722900D02*
X-723567Y-587383D01*
X-724150Y-586917D01*
X-724650Y-586217D01*
X-724983Y-585400D01*
X-725150Y-584467D01*
Y-583533D01*
X-724983Y-582600D01*
X-724650Y-581783D01*
X-724150Y-581083D01*
X-723567Y-580617D01*
X-722900Y-580500D01*
X-722233Y-580617D01*
X-721650Y-581083D01*
X-721150Y-581783D01*
X-720817Y-582600D01*
X-720650Y-583533D01*
Y-584467D01*
X-720817Y-585400D01*
X-721150Y-586217D01*
X-721650Y-586917D01*
X-722233Y-587383D01*
X-722900Y-587500D01*
G01X-718017D02*
Y-580500D01*
X-714183Y-587500D01*
Y-580500D01*
G01X-709300Y-587733D02*
X-709467Y-587617D01*
Y-587383D01*
X-709300Y-587267D01*
X-709133Y-587383D01*
Y-587617D01*
X-709300Y-587733D01*
G01X-870667Y-551083D02*
X-871167Y-550733D01*
X-871750Y-550500D01*
X-872417D01*
X-873167Y-550850D01*
X-873750Y-551433D01*
X-874167Y-552133D01*
X-874500Y-553300D01*
X-874583Y-554350D01*
X-874417Y-555400D01*
X-874167Y-556100D01*
X-873667Y-556800D01*
X-873083Y-557267D01*
X-872500Y-557500D01*
X-871917D01*
X-871333Y-557267D01*
X-870833Y-556917D01*
X-870417Y-556450D01*
G01X-865700Y-557500D02*
X-866367Y-557383D01*
X-866950Y-556917D01*
X-867450Y-556217D01*
X-867783Y-555400D01*
X-867950Y-554467D01*
Y-553533D01*
X-867783Y-552600D01*
X-867450Y-551783D01*
X-866950Y-551083D01*
X-866367Y-550617D01*
X-865700Y-550500D01*
X-865033Y-550617D01*
X-864450Y-551083D01*
X-863950Y-551783D01*
X-863617Y-552600D01*
X-863450Y-553533D01*
Y-554467D01*
X-863617Y-555400D01*
X-863950Y-556217D01*
X-864450Y-556917D01*
X-865033Y-557383D01*
X-865700Y-557500D01*
G01X-860817D02*
Y-550500D01*
X-856983Y-557500D01*
Y-550500D01*
G01X-853683Y-557500D02*
Y-550500D01*
X-850517D01*
G01X-851683Y-553883D02*
X-853683D01*
G01X-846300Y-550500D02*
X-844300D01*
G01X-845300D02*
Y-557500D01*
G01X-846300D02*
X-844300D01*
G01X-840333D02*
Y-550500D01*
X-838667D01*
X-838000Y-550850D01*
X-837500Y-551317D01*
X-837083Y-552017D01*
X-836750Y-552833D01*
X-836667Y-554000D01*
X-836750Y-555167D01*
X-837083Y-555983D01*
X-837500Y-556684D01*
X-838000Y-557150D01*
X-838667Y-557500D01*
X-840333D01*
G01X-830033D02*
X-833367D01*
Y-550500D01*
X-830033D01*
G01X-831367Y-553883D02*
X-833367D01*
G01X-826817Y-557500D02*
Y-550500D01*
X-822983Y-557500D01*
Y-550500D01*
G01X-816267Y-551083D02*
X-816767Y-550733D01*
X-817350Y-550500D01*
X-818017D01*
X-818767Y-550850D01*
X-819350Y-551433D01*
X-819767Y-552133D01*
X-820100Y-553300D01*
X-820183Y-554350D01*
X-820017Y-555400D01*
X-819767Y-556100D01*
X-819267Y-556800D01*
X-818683Y-557267D01*
X-818100Y-557500D01*
X-817517D01*
X-816933Y-557267D01*
X-816433Y-556917D01*
X-816017Y-556450D01*
G01X-809633Y-557500D02*
X-812967D01*
Y-550500D01*
X-809633D01*
G01X-810967Y-553883D02*
X-812967D01*
G01X-799783Y-557500D02*
X-797700Y-550500D01*
X-795617Y-557500D01*
G01X-796367Y-555050D02*
X-799033D01*
G01X-792817Y-557500D02*
Y-550500D01*
X-788983Y-557500D01*
Y-550500D01*
G01X-785933Y-557500D02*
Y-550500D01*
X-784267D01*
X-783600Y-550850D01*
X-783100Y-551317D01*
X-782683Y-552017D01*
X-782350Y-552833D01*
X-782267Y-554000D01*
X-782350Y-555167D01*
X-782683Y-555983D01*
X-783100Y-556684D01*
X-783600Y-557150D01*
X-784267Y-557500D01*
X-785933D01*
G01X-771500Y-550500D02*
X-769500D01*
G01X-770500D02*
Y-557500D01*
G01X-771500D02*
X-769500D01*
G01X-763700Y-550500D02*
Y-557500D01*
G01X-765617Y-550500D02*
X-761783D01*
G01X-758650Y-556567D02*
X-757983Y-557150D01*
X-757233Y-557500D01*
X-756567D01*
X-755900Y-557150D01*
X-755400Y-556567D01*
X-755150Y-555750D01*
X-755317Y-554933D01*
X-755733Y-554233D01*
X-756483Y-553767D01*
X-757483Y-553533D01*
X-758067Y-553067D01*
X-758317Y-552250D01*
X-758150Y-551433D01*
X-757733Y-550850D01*
X-757150Y-550500D01*
X-756567D01*
X-755983Y-550733D01*
X-755483Y-551317D01*
G01X-741467Y-551083D02*
X-741967Y-550733D01*
X-742550Y-550500D01*
X-743217D01*
X-743967Y-550850D01*
X-744550Y-551433D01*
X-744967Y-552133D01*
X-745300Y-553300D01*
X-745383Y-554350D01*
X-745217Y-555400D01*
X-744967Y-556100D01*
X-744467Y-556800D01*
X-743883Y-557267D01*
X-743300Y-557500D01*
X-742717D01*
X-742133Y-557267D01*
X-741633Y-556917D01*
X-741217Y-556450D01*
G01X-736500Y-557500D02*
X-737167Y-557383D01*
X-737750Y-556917D01*
X-738250Y-556217D01*
X-738583Y-555400D01*
X-738750Y-554467D01*
Y-553533D01*
X-738583Y-552600D01*
X-738250Y-551783D01*
X-737750Y-551083D01*
X-737167Y-550617D01*
X-736500Y-550500D01*
X-735833Y-550617D01*
X-735250Y-551083D01*
X-734750Y-551783D01*
X-734417Y-552600D01*
X-734250Y-553533D01*
Y-554467D01*
X-734417Y-555400D01*
X-734750Y-556217D01*
X-735250Y-556917D01*
X-735833Y-557383D01*
X-736500Y-557500D01*
G01X-731617D02*
Y-550500D01*
X-727783Y-557500D01*
Y-550500D01*
G01X-722900D02*
Y-557500D01*
G01X-724817Y-550500D02*
X-720983D01*
G01X-714433Y-557500D02*
X-717767D01*
Y-550500D01*
X-714433D01*
G01X-715767Y-553883D02*
X-717767D01*
G01X-711217Y-557500D02*
Y-550500D01*
X-707383Y-557500D01*
Y-550500D01*
G01X-702500D02*
Y-557500D01*
G01X-704417Y-550500D02*
X-700583D01*
G01X-697450Y-556567D02*
X-696783Y-557150D01*
X-696033Y-557500D01*
X-695367D01*
X-694700Y-557150D01*
X-694200Y-556567D01*
X-693950Y-555750D01*
X-694117Y-554933D01*
X-694533Y-554233D01*
X-695283Y-553767D01*
X-696283Y-553533D01*
X-696867Y-553067D01*
X-697117Y-552250D01*
X-696950Y-551433D01*
X-696533Y-550850D01*
X-695950Y-550500D01*
X-695367D01*
X-694783Y-550733D01*
X-694283Y-551317D01*
G01X-684267Y-557500D02*
Y-550500D01*
X-682100Y-556333D01*
X-679933Y-550500D01*
Y-557500D01*
G01X-677383D02*
X-675300Y-550500D01*
X-673217Y-557500D01*
G01X-673967Y-555050D02*
X-676633D01*
G01X-668500Y-557500D02*
Y-554350D01*
X-670167Y-550500D01*
G01X-666833D02*
X-668500Y-554350D01*
G01X-656817Y-557500D02*
Y-550500D01*
X-652983Y-557500D01*
Y-550500D01*
G01X-648100Y-557500D02*
X-648767Y-557383D01*
X-649350Y-556917D01*
X-649850Y-556217D01*
X-650183Y-555400D01*
X-650350Y-554467D01*
Y-553533D01*
X-650183Y-552600D01*
X-649850Y-551783D01*
X-649350Y-551083D01*
X-648767Y-550617D01*
X-648100Y-550500D01*
X-647433Y-550617D01*
X-646850Y-551083D01*
X-646350Y-551783D01*
X-646017Y-552600D01*
X-645850Y-553533D01*
Y-554467D01*
X-646017Y-555400D01*
X-646350Y-556217D01*
X-646850Y-556917D01*
X-647433Y-557383D01*
X-648100Y-557500D01*
G01X-641300Y-550500D02*
Y-557500D01*
G01X-643217Y-550500D02*
X-639383D01*
G01X-627033Y-553767D02*
X-626700Y-553417D01*
X-626450Y-552833D01*
X-626283Y-552017D01*
X-626450Y-551317D01*
X-626783Y-550850D01*
X-627367Y-550500D01*
X-629617D01*
Y-557500D01*
X-626867D01*
X-626283Y-557033D01*
X-625950Y-556333D01*
X-625783Y-555517D01*
X-625950Y-554700D01*
X-626450Y-554000D01*
X-627033Y-553767D01*
X-629617D01*
G01X-619233Y-557500D02*
X-622567D01*
Y-550500D01*
X-619233D01*
G01X-620567Y-553883D02*
X-622567D01*
G01X-870667Y-536083D02*
X-871167Y-535733D01*
X-871750Y-535500D01*
X-872417D01*
X-873167Y-535850D01*
X-873750Y-536433D01*
X-874167Y-537133D01*
X-874500Y-538300D01*
X-874583Y-539350D01*
X-874417Y-540400D01*
X-874167Y-541100D01*
X-873667Y-541800D01*
X-873083Y-542267D01*
X-872500Y-542500D01*
X-871917D01*
X-871333Y-542267D01*
X-870833Y-541917D01*
X-870417Y-541450D01*
G01X-865700Y-542500D02*
X-866367Y-542383D01*
X-866950Y-541917D01*
X-867450Y-541217D01*
X-867783Y-540400D01*
X-867950Y-539467D01*
Y-538533D01*
X-867783Y-537600D01*
X-867450Y-536783D01*
X-866950Y-536083D01*
X-866367Y-535617D01*
X-865700Y-535500D01*
X-865033Y-535617D01*
X-864450Y-536083D01*
X-863950Y-536783D01*
X-863617Y-537600D01*
X-863450Y-538533D01*
Y-539467D01*
X-863617Y-540400D01*
X-863950Y-541217D01*
X-864450Y-541917D01*
X-865033Y-542383D01*
X-865700Y-542500D01*
G01X-860567D02*
Y-535500D01*
X-858483D01*
X-857817Y-535850D01*
X-857400Y-536317D01*
X-857233Y-537250D01*
X-857400Y-538183D01*
X-857900Y-538767D01*
X-858483Y-539117D01*
X-860567D01*
G01X-858483D02*
X-857233Y-542500D01*
G01X-853767D02*
Y-535500D01*
X-851767D01*
X-851100Y-535850D01*
X-850600Y-536667D01*
X-850433Y-537600D01*
X-850600Y-538533D01*
X-851017Y-539233D01*
X-851767Y-539584D01*
X-853767D01*
G01X-845300Y-542500D02*
X-845967Y-542383D01*
X-846550Y-541917D01*
X-847050Y-541217D01*
X-847383Y-540400D01*
X-847550Y-539467D01*
Y-538533D01*
X-847383Y-537600D01*
X-847050Y-536783D01*
X-846550Y-536083D01*
X-845967Y-535617D01*
X-845300Y-535500D01*
X-844633Y-535617D01*
X-844050Y-536083D01*
X-843550Y-536783D01*
X-843217Y-537600D01*
X-843050Y-538533D01*
Y-539467D01*
X-843217Y-540400D01*
X-843550Y-541217D01*
X-844050Y-541917D01*
X-844633Y-542383D01*
X-845300Y-542500D01*
G01X-840167D02*
Y-535500D01*
X-838083D01*
X-837417Y-535850D01*
X-837000Y-536317D01*
X-836833Y-537250D01*
X-837000Y-538183D01*
X-837500Y-538767D01*
X-838083Y-539117D01*
X-840167D01*
G01X-838083D02*
X-836833Y-542500D01*
G01X-833783D02*
X-831700Y-535500D01*
X-829617Y-542500D01*
G01X-830367Y-540050D02*
X-833033D01*
G01X-824900Y-535500D02*
Y-542500D01*
G01X-826817Y-535500D02*
X-822983D01*
G01X-819100D02*
X-817100D01*
G01X-818100D02*
Y-542500D01*
G01X-819100D02*
X-817100D01*
G01X-811300D02*
X-811967Y-542383D01*
X-812550Y-541917D01*
X-813050Y-541217D01*
X-813383Y-540400D01*
X-813550Y-539467D01*
Y-538533D01*
X-813383Y-537600D01*
X-813050Y-536783D01*
X-812550Y-536083D01*
X-811967Y-535617D01*
X-811300Y-535500D01*
X-810633Y-535617D01*
X-810050Y-536083D01*
X-809550Y-536783D01*
X-809217Y-537600D01*
X-809050Y-538533D01*
Y-539467D01*
X-809217Y-540400D01*
X-809550Y-541217D01*
X-810050Y-541917D01*
X-810633Y-542383D01*
X-811300Y-542500D01*
G01X-806417D02*
Y-535500D01*
X-802583Y-542500D01*
Y-535500D01*
G01X-797700Y-542733D02*
X-797867Y-542617D01*
Y-542383D01*
X-797700Y-542267D01*
X-797533Y-542383D01*
Y-542617D01*
X-797700Y-542733D01*
G01X-784100Y-535500D02*
Y-542500D01*
G01X-786017Y-535500D02*
X-782183D01*
G01X-779050Y-542500D02*
Y-535500D01*
G01X-775550D02*
Y-542500D01*
G01Y-539000D02*
X-779050D01*
G01X-771500Y-535500D02*
X-769500D01*
G01X-770500D02*
Y-542500D01*
G01X-771500D02*
X-769500D01*
G01X-765450Y-541567D02*
X-764783Y-542150D01*
X-764033Y-542500D01*
X-763367D01*
X-762700Y-542150D01*
X-762200Y-541567D01*
X-761950Y-540750D01*
X-762117Y-539933D01*
X-762533Y-539233D01*
X-763283Y-538767D01*
X-764283Y-538533D01*
X-764867Y-538067D01*
X-765117Y-537250D01*
X-764950Y-536433D01*
X-764533Y-535850D01*
X-763950Y-535500D01*
X-763367D01*
X-762783Y-535733D01*
X-762283Y-536317D01*
G01X-751933Y-542500D02*
Y-535500D01*
X-750267D01*
X-749600Y-535850D01*
X-749100Y-536317D01*
X-748683Y-537017D01*
X-748350Y-537833D01*
X-748267Y-539000D01*
X-748350Y-540167D01*
X-748683Y-540983D01*
X-749100Y-541684D01*
X-749600Y-542150D01*
X-750267Y-542500D01*
X-751933D01*
G01X-744967D02*
Y-535500D01*
X-742883D01*
X-742217Y-535850D01*
X-741800Y-536317D01*
X-741633Y-537250D01*
X-741800Y-538183D01*
X-742300Y-538767D01*
X-742883Y-539117D01*
X-744967D01*
G01X-742883D02*
X-741633Y-542500D01*
G01X-738583D02*
X-736500Y-535500D01*
X-734417Y-542500D01*
G01X-735167Y-540050D02*
X-737833D01*
G01X-732200Y-535500D02*
X-731033Y-542500D01*
X-729700Y-535500D01*
X-728367Y-542500D01*
X-727200Y-535500D01*
G01X-723900D02*
X-721900D01*
G01X-722900D02*
Y-542500D01*
G01X-723900D02*
X-721900D01*
G01X-718017D02*
Y-535500D01*
X-714183Y-542500D01*
Y-535500D01*
G01X-708800Y-539000D02*
X-707133D01*
Y-541100D01*
X-707633Y-541800D01*
X-708217Y-542267D01*
X-709050Y-542500D01*
X-709883Y-542267D01*
X-710467Y-541800D01*
X-710967Y-541100D01*
X-711300Y-540283D01*
X-711467Y-539350D01*
Y-538533D01*
X-711300Y-537833D01*
X-710967Y-537017D01*
X-710467Y-536317D01*
X-709967Y-535850D01*
X-709300Y-535500D01*
X-708717D01*
X-708050Y-535733D01*
X-707550Y-536200D01*
G01X-696700Y-535500D02*
X-694700D01*
G01X-695700D02*
Y-542500D01*
G01X-696700D02*
X-694700D01*
G01X-690650Y-541567D02*
X-689983Y-542150D01*
X-689233Y-542500D01*
X-688567D01*
X-687900Y-542150D01*
X-687400Y-541567D01*
X-687150Y-540750D01*
X-687317Y-539933D01*
X-687733Y-539233D01*
X-688483Y-538767D01*
X-689483Y-538533D01*
X-690067Y-538067D01*
X-690317Y-537250D01*
X-690150Y-536433D01*
X-689733Y-535850D01*
X-689150Y-535500D01*
X-688567D01*
X-687983Y-535733D01*
X-687483Y-536317D01*
G01X-676967Y-542500D02*
Y-535500D01*
X-674883D01*
X-674217Y-535850D01*
X-673800Y-536317D01*
X-673633Y-537250D01*
X-673800Y-538183D01*
X-674300Y-538767D01*
X-674883Y-539117D01*
X-676967D01*
G01X-674883D02*
X-673633Y-542500D01*
G01X-666833D02*
X-670167D01*
Y-535500D01*
X-666833D01*
G01X-668167Y-538883D02*
X-670167D01*
G01X-659867Y-536083D02*
X-660367Y-535733D01*
X-660950Y-535500D01*
X-661617D01*
X-662367Y-535850D01*
X-662950Y-536433D01*
X-663367Y-537133D01*
X-663700Y-538300D01*
X-663783Y-539350D01*
X-663617Y-540400D01*
X-663367Y-541100D01*
X-662867Y-541800D01*
X-662283Y-542267D01*
X-661700Y-542500D01*
X-661117D01*
X-660533Y-542267D01*
X-660033Y-541917D01*
X-659617Y-541450D01*
G01X-653233Y-542500D02*
X-656567D01*
Y-535500D01*
X-653233D01*
G01X-654567Y-538883D02*
X-656567D01*
G01X-649100Y-535500D02*
X-647100D01*
G01X-648100D02*
Y-542500D01*
G01X-649100D02*
X-647100D01*
G01X-643383Y-535500D02*
X-641300Y-542500D01*
X-639217Y-535500D01*
G01X-632833Y-542500D02*
X-636167D01*
Y-535500D01*
X-632833D01*
G01X-634167Y-538883D02*
X-636167D01*
G01X-629533Y-542500D02*
Y-535500D01*
X-627867D01*
X-627200Y-535850D01*
X-626700Y-536317D01*
X-626283Y-537017D01*
X-625950Y-537833D01*
X-625867Y-539000D01*
X-625950Y-540167D01*
X-626283Y-540983D01*
X-626700Y-541684D01*
X-627200Y-542150D01*
X-627867Y-542500D01*
X-629533D01*
G01X-615100Y-535500D02*
X-613100D01*
G01X-614100D02*
Y-542500D01*
G01X-615100D02*
X-613100D01*
G01X-609217D02*
Y-535500D01*
X-605383Y-542500D01*
Y-535500D01*
G01X-872500Y-520500D02*
Y-527500D01*
G01X-874417Y-520500D02*
X-870583D01*
G01X-867450Y-527500D02*
Y-520500D01*
G01X-863950D02*
Y-527500D01*
G01Y-524000D02*
X-867450D01*
G01X-857233Y-527500D02*
X-860567D01*
Y-520500D01*
X-857233D01*
G01X-858567Y-523883D02*
X-860567D01*
G01X-846967Y-527500D02*
Y-520500D01*
X-844967D01*
X-844300Y-520850D01*
X-843800Y-521667D01*
X-843633Y-522600D01*
X-843800Y-523533D01*
X-844217Y-524233D01*
X-844967Y-524584D01*
X-846967D01*
G01X-840167Y-527500D02*
Y-520500D01*
X-838083D01*
X-837417Y-520850D01*
X-837000Y-521317D01*
X-836833Y-522250D01*
X-837000Y-523183D01*
X-837500Y-523767D01*
X-838083Y-524117D01*
X-840167D01*
G01X-838083D02*
X-836833Y-527500D01*
G01X-831700D02*
X-832367Y-527383D01*
X-832950Y-526917D01*
X-833450Y-526217D01*
X-833783Y-525400D01*
X-833950Y-524467D01*
Y-523533D01*
X-833783Y-522600D01*
X-833450Y-521783D01*
X-832950Y-521083D01*
X-832367Y-520617D01*
X-831700Y-520500D01*
X-831033Y-520617D01*
X-830450Y-521083D01*
X-829950Y-521783D01*
X-829617Y-522600D01*
X-829450Y-523533D01*
Y-524467D01*
X-829617Y-525400D01*
X-829950Y-526217D01*
X-830450Y-526917D01*
X-831033Y-527383D01*
X-831700Y-527500D01*
G01X-826567D02*
Y-520500D01*
X-824567D01*
X-823900Y-520850D01*
X-823400Y-521667D01*
X-823233Y-522600D01*
X-823400Y-523533D01*
X-823817Y-524233D01*
X-824567Y-524584D01*
X-826567D01*
G01X-819767Y-527500D02*
Y-520500D01*
X-817683D01*
X-817017Y-520850D01*
X-816600Y-521317D01*
X-816433Y-522250D01*
X-816600Y-523183D01*
X-817100Y-523767D01*
X-817683Y-524117D01*
X-819767D01*
G01X-817683D02*
X-816433Y-527500D01*
G01X-812300Y-520500D02*
X-810300D01*
G01X-811300D02*
Y-527500D01*
G01X-812300D02*
X-810300D01*
G01X-802833D02*
X-806167D01*
Y-520500D01*
X-802833D01*
G01X-804167Y-523883D02*
X-806167D01*
G01X-797700Y-520500D02*
Y-527500D01*
G01X-799617Y-520500D02*
X-795783D01*
G01X-792983Y-527500D02*
X-790900Y-520500D01*
X-788817Y-527500D01*
G01X-789567Y-525050D02*
X-792233D01*
G01X-785767Y-527500D02*
Y-520500D01*
X-783683D01*
X-783017Y-520850D01*
X-782600Y-521317D01*
X-782433Y-522250D01*
X-782600Y-523183D01*
X-783100Y-523767D01*
X-783683Y-524117D01*
X-785767D01*
G01X-783683D02*
X-782433Y-527500D01*
G01X-777300D02*
Y-524350D01*
X-778967Y-520500D01*
G01X-775633D02*
X-777300Y-524350D01*
G01X-765367Y-527500D02*
Y-520500D01*
X-763367D01*
X-762700Y-520850D01*
X-762200Y-521667D01*
X-762033Y-522600D01*
X-762200Y-523533D01*
X-762617Y-524233D01*
X-763367Y-524584D01*
X-765367D01*
G01X-758567Y-527500D02*
Y-520500D01*
X-756483D01*
X-755817Y-520850D01*
X-755400Y-521317D01*
X-755233Y-522250D01*
X-755400Y-523183D01*
X-755900Y-523767D01*
X-756483Y-524117D01*
X-758567D01*
G01X-756483D02*
X-755233Y-527500D01*
G01X-750100D02*
X-750767Y-527383D01*
X-751350Y-526917D01*
X-751850Y-526217D01*
X-752183Y-525400D01*
X-752350Y-524467D01*
Y-523533D01*
X-752183Y-522600D01*
X-751850Y-521783D01*
X-751350Y-521083D01*
X-750767Y-520617D01*
X-750100Y-520500D01*
X-749433Y-520617D01*
X-748850Y-521083D01*
X-748350Y-521783D01*
X-748017Y-522600D01*
X-747850Y-523533D01*
Y-524467D01*
X-748017Y-525400D01*
X-748350Y-526217D01*
X-748850Y-526917D01*
X-749433Y-527383D01*
X-750100Y-527500D01*
G01X-744967D02*
Y-520500D01*
X-742967D01*
X-742300Y-520850D01*
X-741800Y-521667D01*
X-741633Y-522600D01*
X-741800Y-523533D01*
X-742217Y-524233D01*
X-742967Y-524584D01*
X-744967D01*
G01X-734833Y-527500D02*
X-738167D01*
Y-520500D01*
X-734833D01*
G01X-736167Y-523883D02*
X-738167D01*
G01X-731367Y-527500D02*
Y-520500D01*
X-729283D01*
X-728617Y-520850D01*
X-728200Y-521317D01*
X-728033Y-522250D01*
X-728200Y-523183D01*
X-728700Y-523767D01*
X-729283Y-524117D01*
X-731367D01*
G01X-729283D02*
X-728033Y-527500D01*
G01X-722900Y-520500D02*
Y-527500D01*
G01X-724817Y-520500D02*
X-720983D01*
G01X-716100Y-527500D02*
Y-524350D01*
X-717767Y-520500D01*
G01X-714433D02*
X-716100Y-524350D01*
G01X-702500Y-527500D02*
X-703167Y-527383D01*
X-703750Y-526917D01*
X-704250Y-526217D01*
X-704583Y-525400D01*
X-704750Y-524467D01*
Y-523533D01*
X-704583Y-522600D01*
X-704250Y-521783D01*
X-703750Y-521083D01*
X-703167Y-520617D01*
X-702500Y-520500D01*
X-701833Y-520617D01*
X-701250Y-521083D01*
X-700750Y-521783D01*
X-700417Y-522600D01*
X-700250Y-523533D01*
Y-524467D01*
X-700417Y-525400D01*
X-700750Y-526217D01*
X-701250Y-526917D01*
X-701833Y-527383D01*
X-702500Y-527500D01*
G01X-697283D02*
Y-520500D01*
X-694117D01*
G01X-695283Y-523883D02*
X-697283D01*
G01X-684267Y-527500D02*
Y-520500D01*
X-682100Y-526333D01*
X-679933Y-520500D01*
Y-527500D01*
G01X-676300Y-520500D02*
X-674300D01*
G01X-675300D02*
Y-527500D01*
G01X-676300D02*
X-674300D01*
G01X-666667Y-521083D02*
X-667167Y-520733D01*
X-667750Y-520500D01*
X-668417D01*
X-669167Y-520850D01*
X-669750Y-521433D01*
X-670167Y-522133D01*
X-670500Y-523300D01*
X-670583Y-524350D01*
X-670417Y-525400D01*
X-670167Y-526100D01*
X-669667Y-526800D01*
X-669083Y-527267D01*
X-668500Y-527500D01*
X-667917D01*
X-667333Y-527267D01*
X-666833Y-526917D01*
X-666417Y-526450D01*
G01X-663367Y-527500D02*
Y-520500D01*
X-661283D01*
X-660617Y-520850D01*
X-660200Y-521317D01*
X-660033Y-522250D01*
X-660200Y-523183D01*
X-660700Y-523767D01*
X-661283Y-524117D01*
X-663367D01*
G01X-661283D02*
X-660033Y-527500D01*
G01X-654900D02*
X-655567Y-527383D01*
X-656150Y-526917D01*
X-656650Y-526217D01*
X-656983Y-525400D01*
X-657150Y-524467D01*
Y-523533D01*
X-656983Y-522600D01*
X-656650Y-521783D01*
X-656150Y-521083D01*
X-655567Y-520617D01*
X-654900Y-520500D01*
X-654233Y-520617D01*
X-653650Y-521083D01*
X-653150Y-521783D01*
X-652817Y-522600D01*
X-652650Y-523533D01*
Y-524467D01*
X-652817Y-525400D01*
X-653150Y-526217D01*
X-653650Y-526917D01*
X-654233Y-527383D01*
X-654900Y-527500D01*
G01X-649850Y-526567D02*
X-649183Y-527150D01*
X-648433Y-527500D01*
X-647767D01*
X-647100Y-527150D01*
X-646600Y-526567D01*
X-646350Y-525750D01*
X-646517Y-524933D01*
X-646933Y-524233D01*
X-647683Y-523767D01*
X-648683Y-523533D01*
X-649267Y-523067D01*
X-649517Y-522250D01*
X-649350Y-521433D01*
X-648933Y-520850D01*
X-648350Y-520500D01*
X-647767D01*
X-647183Y-520733D01*
X-646683Y-521317D01*
G01X-641300Y-527500D02*
X-641967Y-527383D01*
X-642550Y-526917D01*
X-643050Y-526217D01*
X-643383Y-525400D01*
X-643550Y-524467D01*
Y-523533D01*
X-643383Y-522600D01*
X-643050Y-521783D01*
X-642550Y-521083D01*
X-641967Y-520617D01*
X-641300Y-520500D01*
X-640633Y-520617D01*
X-640050Y-521083D01*
X-639550Y-521783D01*
X-639217Y-522600D01*
X-639050Y-523533D01*
Y-524467D01*
X-639217Y-525400D01*
X-639550Y-526217D01*
X-640050Y-526917D01*
X-640633Y-527383D01*
X-641300Y-527500D01*
G01X-636083D02*
Y-520500D01*
X-632917D01*
G01X-634083Y-523883D02*
X-636083D01*
G01X-627700Y-520500D02*
Y-527500D01*
G01X-629617Y-520500D02*
X-625783D01*
G01X-872500Y-505500D02*
Y-512500D01*
G01X-874417Y-505500D02*
X-870583D01*
G01X-867450Y-512500D02*
Y-505500D01*
G01X-863950D02*
Y-512500D01*
G01Y-509000D02*
X-867450D01*
G01X-859900Y-505500D02*
X-857900D01*
G01X-858900D02*
Y-512500D01*
G01X-859900D02*
X-857900D01*
G01X-853850Y-511567D02*
X-853183Y-512150D01*
X-852433Y-512500D01*
X-851767D01*
X-851100Y-512150D01*
X-850600Y-511567D01*
X-850350Y-510750D01*
X-850517Y-509933D01*
X-850933Y-509233D01*
X-851683Y-508767D01*
X-852683Y-508533D01*
X-853267Y-508067D01*
X-853517Y-507250D01*
X-853350Y-506433D01*
X-852933Y-505850D01*
X-852350Y-505500D01*
X-851767D01*
X-851183Y-505733D01*
X-850683Y-506317D01*
G01X-840333Y-512500D02*
Y-505500D01*
X-838667D01*
X-838000Y-505850D01*
X-837500Y-506317D01*
X-837083Y-507017D01*
X-836750Y-507833D01*
X-836667Y-509000D01*
X-836750Y-510167D01*
X-837083Y-510983D01*
X-837500Y-511684D01*
X-838000Y-512150D01*
X-838667Y-512500D01*
X-840333D01*
G01X-833367D02*
Y-505500D01*
X-831283D01*
X-830617Y-505850D01*
X-830200Y-506317D01*
X-830033Y-507250D01*
X-830200Y-508183D01*
X-830700Y-508767D01*
X-831283Y-509117D01*
X-833367D01*
G01X-831283D02*
X-830033Y-512500D01*
G01X-826983D02*
X-824900Y-505500D01*
X-822817Y-512500D01*
G01X-823567Y-510050D02*
X-826233D01*
G01X-820600Y-505500D02*
X-819433Y-512500D01*
X-818100Y-505500D01*
X-816767Y-512500D01*
X-815600Y-505500D01*
G01X-812300D02*
X-810300D01*
G01X-811300D02*
Y-512500D01*
G01X-812300D02*
X-810300D01*
G01X-806417D02*
Y-505500D01*
X-802583Y-512500D01*
Y-505500D01*
G01X-797200Y-509000D02*
X-795533D01*
Y-511100D01*
X-796033Y-511800D01*
X-796617Y-512267D01*
X-797450Y-512500D01*
X-798283Y-512267D01*
X-798867Y-511800D01*
X-799367Y-511100D01*
X-799700Y-510283D01*
X-799867Y-509350D01*
Y-508533D01*
X-799700Y-507833D01*
X-799367Y-507017D01*
X-798867Y-506317D01*
X-798367Y-505850D01*
X-797700Y-505500D01*
X-797117D01*
X-796450Y-505733D01*
X-795950Y-506200D01*
G01X-782267Y-506083D02*
X-782767Y-505733D01*
X-783350Y-505500D01*
X-784017D01*
X-784767Y-505850D01*
X-785350Y-506433D01*
X-785767Y-507133D01*
X-786100Y-508300D01*
X-786183Y-509350D01*
X-786017Y-510400D01*
X-785767Y-511100D01*
X-785267Y-511800D01*
X-784683Y-512267D01*
X-784100Y-512500D01*
X-783517D01*
X-782933Y-512267D01*
X-782433Y-511917D01*
X-782017Y-511450D01*
G01X-777300Y-512500D02*
X-777967Y-512383D01*
X-778550Y-511917D01*
X-779050Y-511217D01*
X-779383Y-510400D01*
X-779550Y-509467D01*
Y-508533D01*
X-779383Y-507600D01*
X-779050Y-506783D01*
X-778550Y-506083D01*
X-777967Y-505617D01*
X-777300Y-505500D01*
X-776633Y-505617D01*
X-776050Y-506083D01*
X-775550Y-506783D01*
X-775217Y-507600D01*
X-775050Y-508533D01*
Y-509467D01*
X-775217Y-510400D01*
X-775550Y-511217D01*
X-776050Y-511917D01*
X-776633Y-512383D01*
X-777300Y-512500D01*
G01X-772417D02*
Y-505500D01*
X-768583Y-512500D01*
Y-505500D01*
G01X-763700D02*
Y-512500D01*
G01X-765617Y-505500D02*
X-761783D01*
G01X-758983Y-512500D02*
X-756900Y-505500D01*
X-754817Y-512500D01*
G01X-755567Y-510050D02*
X-758233D01*
G01X-751100Y-505500D02*
X-749100D01*
G01X-750100D02*
Y-512500D01*
G01X-751100D02*
X-749100D01*
G01X-745217D02*
Y-505500D01*
X-741383Y-512500D01*
Y-505500D01*
G01X-738250Y-511567D02*
X-737583Y-512150D01*
X-736833Y-512500D01*
X-736167D01*
X-735500Y-512150D01*
X-735000Y-511567D01*
X-734750Y-510750D01*
X-734917Y-509933D01*
X-735333Y-509233D01*
X-736083Y-508767D01*
X-737083Y-508533D01*
X-737667Y-508067D01*
X-737917Y-507250D01*
X-737750Y-506433D01*
X-737333Y-505850D01*
X-736750Y-505500D01*
X-736167D01*
X-735583Y-505733D01*
X-735083Y-506317D01*
G01X-723900Y-505500D02*
X-721900D01*
G01X-722900D02*
Y-512500D01*
G01X-723900D02*
X-721900D01*
G01X-718017D02*
Y-505500D01*
X-714183Y-512500D01*
Y-505500D01*
G01X-710883Y-512500D02*
Y-505500D01*
X-707717D01*
G01X-708883Y-508883D02*
X-710883D01*
G01X-702500Y-512500D02*
X-703167Y-512383D01*
X-703750Y-511917D01*
X-704250Y-511217D01*
X-704583Y-510400D01*
X-704750Y-509467D01*
Y-508533D01*
X-704583Y-507600D01*
X-704250Y-506783D01*
X-703750Y-506083D01*
X-703167Y-505617D01*
X-702500Y-505500D01*
X-701833Y-505617D01*
X-701250Y-506083D01*
X-700750Y-506783D01*
X-700417Y-507600D01*
X-700250Y-508533D01*
Y-509467D01*
X-700417Y-510400D01*
X-700750Y-511217D01*
X-701250Y-511917D01*
X-701833Y-512383D01*
X-702500Y-512500D01*
G01X-697367D02*
Y-505500D01*
X-695283D01*
X-694617Y-505850D01*
X-694200Y-506317D01*
X-694033Y-507250D01*
X-694200Y-508183D01*
X-694700Y-508767D01*
X-695283Y-509117D01*
X-697367D01*
G01X-695283D02*
X-694033Y-512500D01*
G01X-691067D02*
Y-505500D01*
X-688900Y-511333D01*
X-686733Y-505500D01*
Y-512500D01*
G01X-684183D02*
X-682100Y-505500D01*
X-680017Y-512500D01*
G01X-680767Y-510050D02*
X-683433D01*
G01X-675300Y-505500D02*
Y-512500D01*
G01X-677217Y-505500D02*
X-673383D01*
G01X-669500D02*
X-667500D01*
G01X-668500D02*
Y-512500D01*
G01X-669500D02*
X-667500D01*
G01X-661700D02*
X-662367Y-512383D01*
X-662950Y-511917D01*
X-663450Y-511217D01*
X-663783Y-510400D01*
X-663950Y-509467D01*
Y-508533D01*
X-663783Y-507600D01*
X-663450Y-506783D01*
X-662950Y-506083D01*
X-662367Y-505617D01*
X-661700Y-505500D01*
X-661033Y-505617D01*
X-660450Y-506083D01*
X-659950Y-506783D01*
X-659617Y-507600D01*
X-659450Y-508533D01*
Y-509467D01*
X-659617Y-510400D01*
X-659950Y-511217D01*
X-660450Y-511917D01*
X-661033Y-512383D01*
X-661700Y-512500D01*
G01X-656817D02*
Y-505500D01*
X-652983Y-512500D01*
Y-505500D01*
G01X-643800D02*
X-642633Y-512500D01*
X-641300Y-505500D01*
X-639967Y-512500D01*
X-638800Y-505500D01*
G01X-636250Y-512500D02*
Y-505500D01*
G01X-632750D02*
Y-512500D01*
G01Y-509000D02*
X-636250D01*
G01X-628700Y-505500D02*
X-626700D01*
G01X-627700D02*
Y-512500D01*
G01X-628700D02*
X-626700D01*
G01X-619067Y-506083D02*
X-619567Y-505733D01*
X-620150Y-505500D01*
X-620817D01*
X-621567Y-505850D01*
X-622150Y-506433D01*
X-622567Y-507133D01*
X-622900Y-508300D01*
X-622983Y-509350D01*
X-622817Y-510400D01*
X-622567Y-511100D01*
X-622067Y-511800D01*
X-621483Y-512267D01*
X-620900Y-512500D01*
X-620317D01*
X-619733Y-512267D01*
X-619233Y-511917D01*
X-618817Y-511450D01*
G01X-615850Y-512500D02*
Y-505500D01*
G01X-612350D02*
Y-512500D01*
G01Y-509000D02*
X-615850D01*
G01X-601500Y-505500D02*
X-599500D01*
G01X-600500D02*
Y-512500D01*
G01X-601500D02*
X-599500D01*
G01X-595450Y-511567D02*
X-594783Y-512150D01*
X-594033Y-512500D01*
X-593367D01*
X-592700Y-512150D01*
X-592200Y-511567D01*
X-591950Y-510750D01*
X-592117Y-509933D01*
X-592533Y-509233D01*
X-593283Y-508767D01*
X-594283Y-508533D01*
X-594867Y-508067D01*
X-595117Y-507250D01*
X-594950Y-506433D01*
X-594533Y-505850D01*
X-593950Y-505500D01*
X-593367D01*
X-592783Y-505733D01*
X-592283Y-506317D01*
G01X-858133Y-452500D02*
Y-445500D01*
X-856467D01*
X-855800Y-445850D01*
X-855300Y-446317D01*
X-854883Y-447017D01*
X-854550Y-447833D01*
X-854467Y-449000D01*
X-854550Y-450167D01*
X-854883Y-450983D01*
X-855300Y-451684D01*
X-855800Y-452150D01*
X-856467Y-452500D01*
X-858133D01*
G01X-847833D02*
X-851167D01*
Y-445500D01*
X-847833D01*
G01X-849167Y-448883D02*
X-851167D01*
G01X-844450Y-451567D02*
X-843783Y-452150D01*
X-843033Y-452500D01*
X-842367D01*
X-841700Y-452150D01*
X-841200Y-451567D01*
X-840950Y-450750D01*
X-841117Y-449933D01*
X-841533Y-449233D01*
X-842283Y-448767D01*
X-843283Y-448533D01*
X-843867Y-448067D01*
X-844117Y-447250D01*
X-843950Y-446433D01*
X-843533Y-445850D01*
X-842950Y-445500D01*
X-842367D01*
X-841783Y-445733D01*
X-841283Y-446317D01*
G01X-836900Y-445500D02*
X-834900D01*
G01X-835900D02*
Y-452500D01*
G01X-836900D02*
X-834900D01*
G01X-828600Y-449000D02*
X-826933D01*
Y-451100D01*
X-827433Y-451800D01*
X-828017Y-452267D01*
X-828850Y-452500D01*
X-829683Y-452267D01*
X-830267Y-451800D01*
X-830767Y-451100D01*
X-831100Y-450283D01*
X-831267Y-449350D01*
Y-448533D01*
X-831100Y-447833D01*
X-830767Y-447017D01*
X-830267Y-446317D01*
X-829767Y-445850D01*
X-829100Y-445500D01*
X-828517D01*
X-827850Y-445733D01*
X-827350Y-446200D01*
G01X-824217Y-452500D02*
Y-445500D01*
X-820383Y-452500D01*
Y-445500D01*
G01X-813833Y-452500D02*
X-817167D01*
Y-445500D01*
X-813833D01*
G01X-815167Y-448883D02*
X-817167D01*
G01X-810367Y-452500D02*
Y-445500D01*
X-808283D01*
X-807617Y-445850D01*
X-807200Y-446317D01*
X-807033Y-447250D01*
X-807200Y-448183D01*
X-807700Y-448767D01*
X-808283Y-449117D01*
X-810367D01*
G01X-808283D02*
X-807033Y-452500D01*
G01X-858133D02*
Y-445500D01*
X-856467D01*
X-855800Y-445850D01*
X-855300Y-446317D01*
X-854883Y-447017D01*
X-854550Y-447833D01*
X-854467Y-449000D01*
X-854550Y-450167D01*
X-854883Y-450983D01*
X-855300Y-451684D01*
X-855800Y-452150D01*
X-856467Y-452500D01*
X-858133D01*
G01X-847833D02*
X-851167D01*
Y-445500D01*
X-847833D01*
G01X-849167Y-448883D02*
X-851167D01*
G01X-844450Y-451567D02*
X-843783Y-452150D01*
X-843033Y-452500D01*
X-842367D01*
X-841700Y-452150D01*
X-841200Y-451567D01*
X-840950Y-450750D01*
X-841117Y-449933D01*
X-841533Y-449233D01*
X-842283Y-448767D01*
X-843283Y-448533D01*
X-843867Y-448067D01*
X-844117Y-447250D01*
X-843950Y-446433D01*
X-843533Y-445850D01*
X-842950Y-445500D01*
X-842367D01*
X-841783Y-445733D01*
X-841283Y-446317D01*
G01X-836900Y-445500D02*
X-834900D01*
G01X-835900D02*
Y-452500D01*
G01X-836900D02*
X-834900D01*
G01X-828600Y-449000D02*
X-826933D01*
Y-451100D01*
X-827433Y-451800D01*
X-828017Y-452267D01*
X-828850Y-452500D01*
X-829683Y-452267D01*
X-830267Y-451800D01*
X-830767Y-451100D01*
X-831100Y-450283D01*
X-831267Y-449350D01*
Y-448533D01*
X-831100Y-447833D01*
X-830767Y-447017D01*
X-830267Y-446317D01*
X-829767Y-445850D01*
X-829100Y-445500D01*
X-828517D01*
X-827850Y-445733D01*
X-827350Y-446200D01*
G01X-824217Y-452500D02*
Y-445500D01*
X-820383Y-452500D01*
Y-445500D01*
G01X-813833Y-452500D02*
X-817167D01*
Y-445500D01*
X-813833D01*
G01X-815167Y-448883D02*
X-817167D01*
G01X-810367Y-452500D02*
Y-445500D01*
X-808283D01*
X-807617Y-445850D01*
X-807200Y-446317D01*
X-807033Y-447250D01*
X-807200Y-448183D01*
X-807700Y-448767D01*
X-808283Y-449117D01*
X-810367D01*
G01X-808283D02*
X-807033Y-452500D01*
G01X-642033Y-455000D02*
Y-448000D01*
X-640367D01*
X-639700Y-448350D01*
X-639200Y-448817D01*
X-638783Y-449517D01*
X-638450Y-450333D01*
X-638367Y-451500D01*
X-638450Y-452667D01*
X-638783Y-453483D01*
X-639200Y-454184D01*
X-639700Y-454650D01*
X-640367Y-455000D01*
X-642033D01*
G01X-635483D02*
X-633400Y-448000D01*
X-631317Y-455000D01*
G01X-632067Y-452550D02*
X-634733D01*
G01X-626600Y-448000D02*
Y-455000D01*
G01X-628517Y-448000D02*
X-624683D01*
G01X-618133Y-455000D02*
X-621467D01*
Y-448000D01*
X-618133D01*
G01X-619467Y-451383D02*
X-621467D01*
G54D39*
X-1003346Y-36375D03*
X-960039D03*
X-133268D03*
X-89961D03*
G54D49*
G01X-1020800Y-457700D02*
G02X-1020300Y-458200I0J-500D01*
G01Y-458400D01*
G02X-1020900Y-459000I-600J0D01*
G01X-1021300D01*
G01X-1021800Y-460500D02*
Y-457700D01*
X-1020600D01*
G01X-1018340Y-459100D02*
G03I-2660J0D01*
G01X-1020700D02*
X-1020200Y-460500D01*
M02*
